FILE_TYPE = MACRO_DRAWING;
SET COLOR_WIRE YELLOW;
SET COLOR_PROP ORANGE;
SET COLOR_DOT WHITE;
SET COLOR_ARC YELLOW;
SET COLOR_BODY GREEN;
SET COLOR_NOTE PURPLE;
SET PROP_DISPLAY VALUE;
SET PAGE_NUMBER P52;
FORCEADD GENOA_SP5..18
(-4625 2350);
FORCEPROP 1 LAST LOCATION U26
J 0
(-5225 3550);
DISPLAY 0.489362 (-5225 3550);
PAINT SKYBLUE (-5225 3550);
FORCEPROP 0 LAST $SEC 18
J 0
(-5200 3650);
DISPLAY 0.680851 (-5200 3650);
PAINT MONO (-5200 3650);
DISPLAY INVISIBLE (-5200 3650);
FORCEPROP 0 LAST CDS_SEC 18
J 0
(-5225 3550);
DISPLAY 1.021277 (-5225 3550);
DISPLAY INVISIBLE (-5225 3550);
FORCEPROP 0 LASTPIN (-5375 3100) $PN CV36
J 2
(-5385 3110);
DISPLAY 0.489362 (-5385 3110);
PAINT MONO (-5385 3110);
FORCEPROP 0 LASTPIN (-5375 3000) $PN CY36
J 2
(-5385 3010);
DISPLAY 0.489362 (-5385 3010);
PAINT MONO (-5385 3010);
FORCEPROP 0 LASTPIN (-5375 2900) $PN DB36
J 2
(-5385 2910);
DISPLAY 0.489362 (-5385 2910);
PAINT MONO (-5385 2910);
FORCEPROP 0 LASTPIN (-5375 2800) $PN CW33
J 2
(-5385 2810);
DISPLAY 0.489362 (-5385 2810);
PAINT MONO (-5385 2810);
FORCEPROP 0 LASTPIN (-5375 2700) $PN DC33
J 2
(-5385 2710);
DISPLAY 0.489362 (-5385 2710);
PAINT MONO (-5385 2710);
FORCEPROP 0 LASTPIN (-5375 2600) $PN DA33
J 2
(-5385 2610);
DISPLAY 0.489362 (-5385 2610);
PAINT MONO (-5385 2610);
FORCEPROP 0 LASTPIN (-5375 2500) $PN CW30
J 2
(-5385 2510);
DISPLAY 0.489362 (-5385 2510);
PAINT MONO (-5385 2510);
FORCEPROP 0 LASTPIN (-5375 2400) $PN DC30
J 2
(-5385 2410);
DISPLAY 0.489362 (-5385 2410);
PAINT MONO (-5385 2410);
FORCEPROP 0 LASTPIN (-5375 2300) $PN DA30
J 2
(-5385 2310);
DISPLAY 0.489362 (-5385 2310);
PAINT MONO (-5385 2310);
FORCEPROP 0 LASTPIN (-5375 2200) $PN CW27
J 2
(-5385 2210);
DISPLAY 0.489362 (-5385 2210);
PAINT MONO (-5385 2210);
FORCEPROP 0 LASTPIN (-5375 2100) $PN DC27
J 2
(-5385 2110);
DISPLAY 0.489362 (-5385 2110);
PAINT MONO (-5385 2110);
FORCEPROP 0 LASTPIN (-5375 2000) $PN DA27
J 2
(-5385 2010);
DISPLAY 0.489362 (-5385 2010);
PAINT MONO (-5385 2010);
FORCEPROP 0 LASTPIN (-5375 1900) $PN CW24
J 2
(-5385 1910);
DISPLAY 0.489362 (-5385 1910);
PAINT MONO (-5385 1910);
FORCEPROP 0 LASTPIN (-5375 1800) $PN DC24
J 2
(-5385 1810);
DISPLAY 0.489362 (-5385 1810);
PAINT MONO (-5385 1810);
FORCEPROP 0 LASTPIN (-5375 1700) $PN DA24
J 2
(-5385 1710);
DISPLAY 0.489362 (-5385 1710);
PAINT MONO (-5385 1710);
FORCEPROP 0 LASTPIN (-5375 1600) $PN CU24
J 2
(-5385 1610);
DISPLAY 0.489362 (-5385 1610);
PAINT MONO (-5385 1610);
FORCEPROP 0 LASTPIN (-5375 3150) $PN CV35
J 2
(-5385 3160);
DISPLAY 0.489362 (-5385 3160);
PAINT MONO (-5385 3160);
FORCEPROP 0 LASTPIN (-5375 3050) $PN CY35
J 2
(-5385 3060);
DISPLAY 0.489362 (-5385 3060);
PAINT MONO (-5385 3060);
FORCEPROP 0 LASTPIN (-5375 2950) $PN DB35
J 2
(-5385 2960);
DISPLAY 0.489362 (-5385 2960);
PAINT MONO (-5385 2960);
FORCEPROP 0 LASTPIN (-5375 2850) $PN CW32
J 2
(-5385 2860);
DISPLAY 0.489362 (-5385 2860);
PAINT MONO (-5385 2860);
FORCEPROP 0 LASTPIN (-5375 2750) $PN DC32
J 2
(-5385 2760);
DISPLAY 0.489362 (-5385 2760);
PAINT MONO (-5385 2760);
FORCEPROP 0 LASTPIN (-5375 2650) $PN DA32
J 2
(-5385 2660);
DISPLAY 0.489362 (-5385 2660);
PAINT MONO (-5385 2660);
FORCEPROP 0 LASTPIN (-5375 2550) $PN CW29
J 2
(-5385 2560);
DISPLAY 0.489362 (-5385 2560);
PAINT MONO (-5385 2560);
FORCEPROP 0 LASTPIN (-5375 2450) $PN DC29
J 2
(-5385 2460);
DISPLAY 0.489362 (-5385 2460);
PAINT MONO (-5385 2460);
FORCEPROP 0 LASTPIN (-5375 2350) $PN DA29
J 2
(-5385 2360);
DISPLAY 0.489362 (-5385 2360);
PAINT MONO (-5385 2360);
FORCEPROP 0 LASTPIN (-5375 2250) $PN CW26
J 2
(-5385 2260);
DISPLAY 0.489362 (-5385 2260);
PAINT MONO (-5385 2260);
FORCEPROP 0 LASTPIN (-5375 2150) $PN DC26
J 2
(-5385 2160);
DISPLAY 0.489362 (-5385 2160);
PAINT MONO (-5385 2160);
FORCEPROP 0 LASTPIN (-5375 2050) $PN DA26
J 2
(-5385 2060);
DISPLAY 0.489362 (-5385 2060);
PAINT MONO (-5385 2060);
FORCEPROP 0 LASTPIN (-5375 1950) $PN CW23
J 2
(-5385 1960);
DISPLAY 0.489362 (-5385 1960);
PAINT MONO (-5385 1960);
FORCEPROP 0 LASTPIN (-5375 1850) $PN DC23
J 2
(-5385 1860);
DISPLAY 0.489362 (-5385 1860);
PAINT MONO (-5385 1860);
FORCEPROP 0 LASTPIN (-5375 1750) $PN DA23
J 2
(-5385 1760);
DISPLAY 0.489362 (-5385 1760);
PAINT MONO (-5385 1760);
FORCEPROP 0 LASTPIN (-5375 1650) $PN CU23
J 2
(-5385 1660);
DISPLAY 0.489362 (-5385 1660);
PAINT MONO (-5385 1660);
FORCEPROP 0 LASTPIN (-3875 3100) $PN CD35
J 0
(-3865 3110);
DISPLAY 0.489362 (-3865 3110);
PAINT MONO (-3865 3110);
FORCEPROP 0 LASTPIN (-3875 3000) $PN CF35
J 0
(-3865 3010);
DISPLAY 0.489362 (-3865 3010);
PAINT MONO (-3865 3010);
FORCEPROP 0 LASTPIN (-3875 2900) $PN CH35
J 0
(-3865 2910);
DISPLAY 0.489362 (-3865 2910);
PAINT MONO (-3865 2910);
FORCEPROP 0 LASTPIN (-3875 2800) $PN CC32
J 0
(-3865 2810);
DISPLAY 0.489362 (-3865 2810);
PAINT MONO (-3865 2810);
FORCEPROP 0 LASTPIN (-3875 2700) $PN CJ32
J 0
(-3865 2710);
DISPLAY 0.489362 (-3865 2710);
PAINT MONO (-3865 2710);
FORCEPROP 0 LASTPIN (-3875 2600) $PN CG32
J 0
(-3865 2610);
DISPLAY 0.489362 (-3865 2610);
PAINT MONO (-3865 2610);
FORCEPROP 0 LASTPIN (-3875 2500) $PN CE32
J 0
(-3865 2510);
DISPLAY 0.489362 (-3865 2510);
PAINT MONO (-3865 2510);
FORCEPROP 0 LASTPIN (-3875 2400) $PN CC29
J 0
(-3865 2410);
DISPLAY 0.489362 (-3865 2410);
PAINT MONO (-3865 2410);
FORCEPROP 0 LASTPIN (-3875 2300) $PN CG29
J 0
(-3865 2310);
DISPLAY 0.489362 (-3865 2310);
PAINT MONO (-3865 2310);
FORCEPROP 0 LASTPIN (-3875 2200) $PN CE29
J 0
(-3865 2210);
DISPLAY 0.489362 (-3865 2210);
PAINT MONO (-3865 2210);
FORCEPROP 0 LASTPIN (-3875 2100) $PN CC26
J 0
(-3865 2110);
DISPLAY 0.489362 (-3865 2110);
PAINT MONO (-3865 2110);
FORCEPROP 0 LASTPIN (-3875 2000) $PN CG26
J 0
(-3865 2010);
DISPLAY 0.489362 (-3865 2010);
PAINT MONO (-3865 2010);
FORCEPROP 0 LASTPIN (-3875 1900) $PN CE26
J 0
(-3865 1910);
DISPLAY 0.489362 (-3865 1910);
PAINT MONO (-3865 1910);
FORCEPROP 0 LASTPIN (-3875 1800) $PN CC23
J 0
(-3865 1810);
DISPLAY 0.489362 (-3865 1810);
PAINT MONO (-3865 1810);
FORCEPROP 0 LASTPIN (-3875 1700) $PN CG23
J 0
(-3865 1710);
DISPLAY 0.489362 (-3865 1710);
PAINT MONO (-3865 1710);
FORCEPROP 0 LASTPIN (-3875 1600) $PN CE23
J 0
(-3865 1610);
DISPLAY 0.489362 (-3865 1610);
PAINT MONO (-3865 1610);
FORCEPROP 0 LASTPIN (-3875 3150) $PN CD36
J 0
(-3865 3160);
DISPLAY 0.489362 (-3865 3160);
PAINT MONO (-3865 3160);
FORCEPROP 0 LASTPIN (-3875 3050) $PN CF36
J 0
(-3865 3060);
DISPLAY 0.489362 (-3865 3060);
PAINT MONO (-3865 3060);
FORCEPROP 0 LASTPIN (-3875 2950) $PN CH36
J 0
(-3865 2960);
DISPLAY 0.489362 (-3865 2960);
PAINT MONO (-3865 2960);
FORCEPROP 0 LASTPIN (-3875 2850) $PN CC33
J 0
(-3865 2860);
DISPLAY 0.489362 (-3865 2860);
PAINT MONO (-3865 2860);
FORCEPROP 0 LASTPIN (-3875 2750) $PN CJ33
J 0
(-3865 2760);
DISPLAY 0.489362 (-3865 2760);
PAINT MONO (-3865 2760);
FORCEPROP 0 LASTPIN (-3875 2650) $PN CG33
J 0
(-3865 2660);
DISPLAY 0.489362 (-3865 2660);
PAINT MONO (-3865 2660);
FORCEPROP 0 LASTPIN (-3875 2550) $PN CE33
J 0
(-3865 2560);
DISPLAY 0.489362 (-3865 2560);
PAINT MONO (-3865 2560);
FORCEPROP 0 LASTPIN (-3875 2450) $PN CC30
J 0
(-3865 2460);
DISPLAY 0.489362 (-3865 2460);
PAINT MONO (-3865 2460);
FORCEPROP 0 LASTPIN (-3875 2350) $PN CG30
J 0
(-3865 2360);
DISPLAY 0.489362 (-3865 2360);
PAINT MONO (-3865 2360);
FORCEPROP 0 LASTPIN (-3875 2250) $PN CE30
J 0
(-3865 2260);
DISPLAY 0.489362 (-3865 2260);
PAINT MONO (-3865 2260);
FORCEPROP 0 LASTPIN (-3875 2150) $PN CC27
J 0
(-3865 2160);
DISPLAY 0.489362 (-3865 2160);
PAINT MONO (-3865 2160);
FORCEPROP 0 LASTPIN (-3875 2050) $PN CG27
J 0
(-3865 2060);
DISPLAY 0.489362 (-3865 2060);
PAINT MONO (-3865 2060);
FORCEPROP 0 LASTPIN (-3875 1950) $PN CE27
J 0
(-3865 1960);
DISPLAY 0.489362 (-3865 1960);
PAINT MONO (-3865 1960);
FORCEPROP 0 LASTPIN (-3875 1850) $PN CC24
J 0
(-3865 1860);
DISPLAY 0.489362 (-3865 1860);
PAINT MONO (-3865 1860);
FORCEPROP 0 LASTPIN (-3875 1750) $PN CG24
J 0
(-3865 1760);
DISPLAY 0.489362 (-3865 1760);
PAINT MONO (-3865 1760);
FORCEPROP 0 LASTPIN (-3875 1650) $PN CE24
J 0
(-3865 1660);
DISPLAY 0.489362 (-3865 1660);
PAINT MONO (-3865 1660);
FORCEPROP 1 LAST MATERIAL IO
J 0
(-5220 3332);
DISPLAY 0.489362 (-5220 3332);
PAINT SKYBLUE (-5220 3332);
FORCEPROP 2 LAST VALUE SOCKET6096_13568-001
J 0
(-5225 3380);
DISPLAY 0.489362 (-5225 3380);
PAINT SKYBLUE (-5225 3380);
FORCEPROP 1 LAST PART_NUMBER DGA^6000030
J 0
(-5225 3425);
DISPLAY 0.489362 (-5225 3425);
PAINT SKYBLUE (-5225 3425);
FORCEPROP 2 LAST PART_TYPE SMLF
J 0
(-5225 3475);
DISPLAY 1.021277 (-5225 3475);
FORCEPROP 2 LAST CDS_LIB pure_quanta
J 0
(-4625 2350);
DISPLAY INVISIBLE (-4625 2350);
FORCEPROP 1 LAST CDS_LMAN_SYM_OUTLINE -600,950,600,-950
J 0
(-4625 2350);
DISPLAY 0.468085 (-4625 2350);
PAINT GREEN (-4625 2350);
DISPLAY INVISIBLE (-4625 2350);
FORCEPROP 1 LAST NEEDS_NO_SIZE TRUE
J 0
(-4625 2350);
DISPLAY 0.723404 (-4625 2350);
PAINT GREEN (-4625 2350);
DISPLAY INVISIBLE (-4625 2350);
FORCEPROP 1 LAST PATH I147
J 0
(-4625 2350);
DISPLAY 0.723404 (-4625 2350);
PAINT GREEN (-4625 2350);
DISPLAY INVISIBLE (-4625 2350);
FORCEADD GENOA_SP5..17
(-4625 4850);
FORCEPROP 1 LAST LOCATION U26
J 0
(-5225 6000);
DISPLAY 0.489362 (-5225 6000);
PAINT SKYBLUE (-5225 6000);
FORCEPROP 0 LAST $SEC 17
J 0
(-5200 6150);
DISPLAY 0.680851 (-5200 6150);
PAINT MONO (-5200 6150);
DISPLAY INVISIBLE (-5200 6150);
FORCEPROP 0 LAST CDS_SEC 17
J 0
(-5225 6025);
DISPLAY 1.021277 (-5225 6025);
DISPLAY INVISIBLE (-5225 6025);
FORCEPROP 0 LASTPIN (-5375 5600) $PN CM36
J 2
(-5385 5610);
DISPLAY 0.489362 (-5385 5610);
PAINT MONO (-5385 5610);
FORCEPROP 0 LASTPIN (-5375 5500) $PN CP36
J 2
(-5385 5510);
DISPLAY 0.489362 (-5385 5510);
PAINT MONO (-5385 5510);
FORCEPROP 0 LASTPIN (-5375 5400) $PN CT36
J 2
(-5385 5410);
DISPLAY 0.489362 (-5385 5410);
PAINT MONO (-5385 5410);
FORCEPROP 0 LASTPIN (-5375 5300) $PN CN33
J 2
(-5385 5310);
DISPLAY 0.489362 (-5385 5310);
PAINT MONO (-5385 5310);
FORCEPROP 0 LASTPIN (-5375 5200) $PN CU33
J 2
(-5385 5210);
DISPLAY 0.489362 (-5385 5210);
PAINT MONO (-5385 5210);
FORCEPROP 0 LASTPIN (-5375 5100) $PN CR33
J 2
(-5385 5110);
DISPLAY 0.489362 (-5385 5110);
PAINT MONO (-5385 5110);
FORCEPROP 0 LASTPIN (-5375 5000) $PN CN30
J 2
(-5385 5010);
DISPLAY 0.489362 (-5385 5010);
PAINT MONO (-5385 5010);
FORCEPROP 0 LASTPIN (-5375 4900) $PN CU30
J 2
(-5385 4910);
DISPLAY 0.489362 (-5385 4910);
PAINT MONO (-5385 4910);
FORCEPROP 0 LASTPIN (-5375 4800) $PN CR30
J 2
(-5385 4810);
DISPLAY 0.489362 (-5385 4810);
PAINT MONO (-5385 4810);
FORCEPROP 0 LASTPIN (-5375 4700) $PN CL27
J 2
(-5385 4710);
DISPLAY 0.489362 (-5385 4710);
PAINT MONO (-5385 4710);
FORCEPROP 0 LASTPIN (-5375 4600) $PN CU27
J 2
(-5385 4610);
DISPLAY 0.489362 (-5385 4610);
PAINT MONO (-5385 4610);
FORCEPROP 0 LASTPIN (-5375 4500) $PN CR27
J 2
(-5385 4510);
DISPLAY 0.489362 (-5385 4510);
PAINT MONO (-5385 4510);
FORCEPROP 0 LASTPIN (-5375 4400) $PN CN27
J 2
(-5385 4410);
DISPLAY 0.489362 (-5385 4410);
PAINT MONO (-5385 4410);
FORCEPROP 0 LASTPIN (-5375 4300) $PN CL24
J 2
(-5385 4310);
DISPLAY 0.489362 (-5385 4310);
PAINT MONO (-5385 4310);
FORCEPROP 0 LASTPIN (-5375 4200) $PN CR24
J 2
(-5385 4210);
DISPLAY 0.489362 (-5385 4210);
PAINT MONO (-5385 4210);
FORCEPROP 0 LASTPIN (-5375 4100) $PN CN24
J 2
(-5385 4110);
DISPLAY 0.489362 (-5385 4110);
PAINT MONO (-5385 4110);
FORCEPROP 0 LASTPIN (-5375 5650) $PN CM35
J 2
(-5385 5660);
DISPLAY 0.489362 (-5385 5660);
PAINT MONO (-5385 5660);
FORCEPROP 0 LASTPIN (-5375 5550) $PN CP35
J 2
(-5385 5560);
DISPLAY 0.489362 (-5385 5560);
PAINT MONO (-5385 5560);
FORCEPROP 0 LASTPIN (-5375 5450) $PN CT35
J 2
(-5385 5460);
DISPLAY 0.489362 (-5385 5460);
PAINT MONO (-5385 5460);
FORCEPROP 0 LASTPIN (-5375 5350) $PN CN32
J 2
(-5385 5360);
DISPLAY 0.489362 (-5385 5360);
PAINT MONO (-5385 5360);
FORCEPROP 0 LASTPIN (-5375 5250) $PN CU32
J 2
(-5385 5260);
DISPLAY 0.489362 (-5385 5260);
PAINT MONO (-5385 5260);
FORCEPROP 0 LASTPIN (-5375 5150) $PN CR32
J 2
(-5385 5160);
DISPLAY 0.489362 (-5385 5160);
PAINT MONO (-5385 5160);
FORCEPROP 0 LASTPIN (-5375 5050) $PN CN29
J 2
(-5385 5060);
DISPLAY 0.489362 (-5385 5060);
PAINT MONO (-5385 5060);
FORCEPROP 0 LASTPIN (-5375 4950) $PN CU29
J 2
(-5385 4960);
DISPLAY 0.489362 (-5385 4960);
PAINT MONO (-5385 4960);
FORCEPROP 0 LASTPIN (-5375 4850) $PN CR29
J 2
(-5385 4860);
DISPLAY 0.489362 (-5385 4860);
PAINT MONO (-5385 4860);
FORCEPROP 0 LASTPIN (-5375 4750) $PN CL26
J 2
(-5385 4760);
DISPLAY 0.489362 (-5385 4760);
PAINT MONO (-5385 4760);
FORCEPROP 0 LASTPIN (-5375 4650) $PN CU26
J 2
(-5385 4660);
DISPLAY 0.489362 (-5385 4660);
PAINT MONO (-5385 4660);
FORCEPROP 0 LASTPIN (-5375 4550) $PN CR26
J 2
(-5385 4560);
DISPLAY 0.489362 (-5385 4560);
PAINT MONO (-5385 4560);
FORCEPROP 0 LASTPIN (-5375 4450) $PN CN26
J 2
(-5385 4460);
DISPLAY 0.489362 (-5385 4460);
PAINT MONO (-5385 4460);
FORCEPROP 0 LASTPIN (-5375 4350) $PN CL23
J 2
(-5385 4360);
DISPLAY 0.489362 (-5385 4360);
PAINT MONO (-5385 4360);
FORCEPROP 0 LASTPIN (-5375 4250) $PN CR23
J 2
(-5385 4260);
DISPLAY 0.489362 (-5385 4260);
PAINT MONO (-5385 4260);
FORCEPROP 0 LASTPIN (-5375 4150) $PN CN23
J 2
(-5385 4160);
DISPLAY 0.489362 (-5385 4160);
PAINT MONO (-5385 4160);
FORCEPROP 0 LASTPIN (-3875 5600) $PN BT35
J 0
(-3865 5610);
DISPLAY 0.489362 (-3865 5610);
PAINT MONO (-3865 5610);
FORCEPROP 0 LASTPIN (-3875 5500) $PN BV35
J 0
(-3865 5510);
DISPLAY 0.489362 (-3865 5510);
PAINT MONO (-3865 5510);
FORCEPROP 0 LASTPIN (-3875 5400) $PN CB35
J 0
(-3865 5410);
DISPLAY 0.489362 (-3865 5410);
PAINT MONO (-3865 5410);
FORCEPROP 0 LASTPIN (-3875 5300) $PN BY35
J 0
(-3865 5310);
DISPLAY 0.489362 (-3865 5310);
PAINT MONO (-3865 5310);
FORCEPROP 0 LASTPIN (-3875 5200) $PN BU32
J 0
(-3865 5210);
DISPLAY 0.489362 (-3865 5210);
PAINT MONO (-3865 5210);
FORCEPROP 0 LASTPIN (-3875 5100) $PN CA32
J 0
(-3865 5110);
DISPLAY 0.489362 (-3865 5110);
PAINT MONO (-3865 5110);
FORCEPROP 0 LASTPIN (-3875 5000) $PN BW32
J 0
(-3865 5010);
DISPLAY 0.489362 (-3865 5010);
PAINT MONO (-3865 5010);
FORCEPROP 0 LASTPIN (-3875 4900) $PN BU29
J 0
(-3865 4910);
DISPLAY 0.489362 (-3865 4910);
PAINT MONO (-3865 4910);
FORCEPROP 0 LASTPIN (-3875 4800) $PN CA29
J 0
(-3865 4810);
DISPLAY 0.489362 (-3865 4810);
PAINT MONO (-3865 4810);
FORCEPROP 0 LASTPIN (-3875 4700) $PN BW29
J 0
(-3865 4710);
DISPLAY 0.489362 (-3865 4710);
PAINT MONO (-3865 4710);
FORCEPROP 0 LASTPIN (-3875 4600) $PN BU26
J 0
(-3865 4610);
DISPLAY 0.489362 (-3865 4610);
PAINT MONO (-3865 4610);
FORCEPROP 0 LASTPIN (-3875 4500) $PN CA26
J 0
(-3865 4510);
DISPLAY 0.489362 (-3865 4510);
PAINT MONO (-3865 4510);
FORCEPROP 0 LASTPIN (-3875 4400) $PN BW26
J 0
(-3865 4410);
DISPLAY 0.489362 (-3865 4410);
PAINT MONO (-3865 4410);
FORCEPROP 0 LASTPIN (-3875 4300) $PN BU23
J 0
(-3865 4310);
DISPLAY 0.489362 (-3865 4310);
PAINT MONO (-3865 4310);
FORCEPROP 0 LASTPIN (-3875 4200) $PN CA23
J 0
(-3865 4210);
DISPLAY 0.489362 (-3865 4210);
PAINT MONO (-3865 4210);
FORCEPROP 0 LASTPIN (-3875 4100) $PN BW23
J 0
(-3865 4110);
DISPLAY 0.489362 (-3865 4110);
PAINT MONO (-3865 4110);
FORCEPROP 0 LASTPIN (-3875 5650) $PN BT36
J 0
(-3865 5660);
DISPLAY 0.489362 (-3865 5660);
PAINT MONO (-3865 5660);
FORCEPROP 0 LASTPIN (-3875 5550) $PN BV36
J 0
(-3865 5560);
DISPLAY 0.489362 (-3865 5560);
PAINT MONO (-3865 5560);
FORCEPROP 0 LASTPIN (-3875 5450) $PN CB36
J 0
(-3865 5460);
DISPLAY 0.489362 (-3865 5460);
PAINT MONO (-3865 5460);
FORCEPROP 0 LASTPIN (-3875 5350) $PN BY36
J 0
(-3865 5360);
DISPLAY 0.489362 (-3865 5360);
PAINT MONO (-3865 5360);
FORCEPROP 0 LASTPIN (-3875 5250) $PN BU33
J 0
(-3865 5260);
DISPLAY 0.489362 (-3865 5260);
PAINT MONO (-3865 5260);
FORCEPROP 0 LASTPIN (-3875 5150) $PN CA33
J 0
(-3865 5160);
DISPLAY 0.489362 (-3865 5160);
PAINT MONO (-3865 5160);
FORCEPROP 0 LASTPIN (-3875 5050) $PN BW33
J 0
(-3865 5060);
DISPLAY 0.489362 (-3865 5060);
PAINT MONO (-3865 5060);
FORCEPROP 0 LASTPIN (-3875 4950) $PN BU30
J 0
(-3865 4960);
DISPLAY 0.489362 (-3865 4960);
PAINT MONO (-3865 4960);
FORCEPROP 0 LASTPIN (-3875 4850) $PN CA30
J 0
(-3865 4860);
DISPLAY 0.489362 (-3865 4860);
PAINT MONO (-3865 4860);
FORCEPROP 0 LASTPIN (-3875 4750) $PN BW30
J 0
(-3865 4760);
DISPLAY 0.489362 (-3865 4760);
PAINT MONO (-3865 4760);
FORCEPROP 0 LASTPIN (-3875 4650) $PN BU27
J 0
(-3865 4660);
DISPLAY 0.489362 (-3865 4660);
PAINT MONO (-3865 4660);
FORCEPROP 0 LASTPIN (-3875 4550) $PN CA27
J 0
(-3865 4560);
DISPLAY 0.489362 (-3865 4560);
PAINT MONO (-3865 4560);
FORCEPROP 0 LASTPIN (-3875 4450) $PN BW27
J 0
(-3865 4460);
DISPLAY 0.489362 (-3865 4460);
PAINT MONO (-3865 4460);
FORCEPROP 0 LASTPIN (-3875 4350) $PN BU24
J 0
(-3865 4360);
DISPLAY 0.489362 (-3865 4360);
PAINT MONO (-3865 4360);
FORCEPROP 0 LASTPIN (-3875 4250) $PN CA24
J 0
(-3865 4260);
DISPLAY 0.489362 (-3865 4260);
PAINT MONO (-3865 4260);
FORCEPROP 0 LASTPIN (-3875 4150) $PN BW24
J 0
(-3865 4160);
DISPLAY 0.489362 (-3865 4160);
PAINT MONO (-3865 4160);
FORCEPROP 1 LAST MATERIAL IO
J 0
(-5220 5832);
DISPLAY 0.489362 (-5220 5832);
PAINT SKYBLUE (-5220 5832);
FORCEPROP 2 LAST VALUE SOCKET6096_13568-001
J 0
(-5225 5855);
DISPLAY 0.489362 (-5225 5855);
PAINT SKYBLUE (-5225 5855);
FORCEPROP 1 LAST PART_NUMBER DGA^6000030
J 0
(-5225 5900);
DISPLAY 0.489362 (-5225 5900);
PAINT SKYBLUE (-5225 5900);
FORCEPROP 2 LAST PART_TYPE SMLF
J 0
(-5225 5950);
DISPLAY 1.021277 (-5225 5950);
FORCEPROP 2 LAST CDS_LIB pure_quanta
J 0
(-4625 4850);
DISPLAY INVISIBLE (-4625 4850);
FORCEPROP 1 LAST CDS_LMAN_SYM_OUTLINE -600,950,600,-950
J 0
(-4625 4850);
DISPLAY 0.468085 (-4625 4850);
PAINT GREEN (-4625 4850);
DISPLAY INVISIBLE (-4625 4850);
FORCEPROP 1 LAST NEEDS_NO_SIZE TRUE
J 0
(-4625 4850);
DISPLAY 0.723404 (-4625 4850);
PAINT GREEN (-4625 4850);
DISPLAY INVISIBLE (-4625 4850);
FORCEPROP 1 LAST PATH I148
J 0
(-4625 4850);
DISPLAY 0.723404 (-4625 4850);
PAINT GREEN (-4625 4850);
DISPLAY INVISIBLE (-4625 4850);
FORCEADD OFFPAGE..2
(-2325 5825);
FORCEPROP 2 LAST $XR0 66 
J 0
(-2136 5825);
DISPLAY 0.638298 (-2136 5825);
PAINT MONO (-2136 5825);
FORCEPROP 2 LAST PATH I149
J 0
(-2150 5900);
DISPLAY 1.021277 (-2150 5900);
DISPLAY INVISIBLE (-2150 5900);
FORCEPROP 1 LAST COMMENT_BODY TRUE
J 0
(-2370 5730);
DISPLAY 0.872340 (-2370 5730);
PAINT GREEN (-2370 5730);
DISPLAY INVISIBLE (-2370 5730);
FORCEPROP 1 LAST OFFPAGE TRUE
J 0
(-2000 5700);
DISPLAY 0.872340 (-2000 5700);
PAINT GREEN (-2000 5700);
DISPLAY INVISIBLE (-2000 5700);
FORCEPROP 2 LAST CDS_LIB standard
J 0
(-2325 5825);
DISPLAY INVISIBLE (-2325 5825);
FORCEADD OFFPAGE..2
(-2325 5875);
FORCEPROP 2 LAST $XR0 66 
J 0
(-2136 5875);
DISPLAY 0.638298 (-2136 5875);
PAINT MONO (-2136 5875);
FORCEPROP 2 LAST PATH I150
J 0
(-2150 5950);
DISPLAY 1.021277 (-2150 5950);
DISPLAY INVISIBLE (-2150 5950);
FORCEPROP 1 LAST COMMENT_BODY TRUE
J 0
(-2370 5780);
DISPLAY 0.872340 (-2370 5780);
PAINT GREEN (-2370 5780);
DISPLAY INVISIBLE (-2370 5780);
FORCEPROP 1 LAST OFFPAGE TRUE
J 0
(-2000 5750);
DISPLAY 0.872340 (-2000 5750);
PAINT GREEN (-2000 5750);
DISPLAY INVISIBLE (-2000 5750);
FORCEPROP 2 LAST CDS_LIB standard
J 0
(-2325 5875);
DISPLAY INVISIBLE (-2325 5875);
FORCEADD TAP..6
R 2
(-3450 5650);
FORCEPROP 3 LASTPIN (-3500 5650) SIG_NAME P5E_CPU1_P2_TX_DP<0>
J 0
(-3490 5660);
DISPLAY 0.659574 (-3490 5660);
PAINT MONO (-3490 5660);
DISPLAY INVISIBLE (-3490 5660);
FORCEPROP 1 LASTPIN (-3500 5650) BN 0
J 2
(-3448 5658);
DISPLAY 0.489362 (-3448 5658);
PAINT MONO (-3448 5658);
FORCEPROP 2 LAST CDS_LIB mstr_standard
J 0
(-3450 5650);
DISPLAY INVISIBLE (-3450 5650);
FORCEPROP 2 LAST BOM_COST IO_SLOT
J 0
(-3950 5750);
DISPLAY 0.829787 (-3950 5750);
DISPLAY INVISIBLE (-3950 5750);
FORCEPROP 1 LAST BODY_TYPE PLUMBING
J 2
(-3450 5600);
DISPLAY 0.702128 (-3450 5600);
PAINT GREEN (-3450 5600);
DISPLAY INVISIBLE (-3450 5600);
FORCEPROP 1 LAST HDL_TAP TRUE
J 2
(-3775 5525);
DISPLAY 0.702128 (-3775 5525);
PAINT GREEN (-3775 5525);
DISPLAY INVISIBLE (-3775 5525);
FORCEPROP 1 LAST PATH I151
J 2
(-3448 5650);
DISPLAY 0.872340 (-3448 5650);
PAINT GREEN (-3448 5650);
DISPLAY INVISIBLE (-3448 5650);
FORCEPROP 2 LAST ROOM RISER1
J 0
(-3950 5700);
DISPLAY 0.829787 (-3950 5700);
PAINT RED (-3950 5700);
DISPLAY INVISIBLE (-3950 5700);
FORCEADD TAP..6
R 2
(-3300 5500);
FORCEPROP 3 LASTPIN (-3350 5500) SIG_NAME P5E_CPU1_P2_TX_DN<1>
J 0
(-3340 5510);
DISPLAY 0.659574 (-3340 5510);
PAINT MONO (-3340 5510);
DISPLAY INVISIBLE (-3340 5510);
FORCEPROP 1 LASTPIN (-3350 5500) BN 1
J 2
(-3298 5508);
DISPLAY 0.489362 (-3298 5508);
PAINT MONO (-3298 5508);
FORCEPROP 2 LAST CDS_LIB mstr_standard
J 0
(-3300 5500);
DISPLAY INVISIBLE (-3300 5500);
FORCEPROP 2 LAST BOM_COST IO_SLOT
J 0
(-3800 5600);
DISPLAY 0.829787 (-3800 5600);
DISPLAY INVISIBLE (-3800 5600);
FORCEPROP 1 LAST BODY_TYPE PLUMBING
J 2
(-3300 5450);
DISPLAY 0.702128 (-3300 5450);
PAINT GREEN (-3300 5450);
DISPLAY INVISIBLE (-3300 5450);
FORCEPROP 1 LAST HDL_TAP TRUE
J 2
(-3625 5375);
DISPLAY 0.702128 (-3625 5375);
PAINT GREEN (-3625 5375);
DISPLAY INVISIBLE (-3625 5375);
FORCEPROP 1 LAST PATH I152
J 2
(-3298 5500);
DISPLAY 0.872340 (-3298 5500);
PAINT GREEN (-3298 5500);
DISPLAY INVISIBLE (-3298 5500);
FORCEPROP 2 LAST ROOM RISER1
J 0
(-3800 5550);
DISPLAY 0.829787 (-3800 5550);
PAINT RED (-3800 5550);
DISPLAY INVISIBLE (-3800 5550);
FORCEADD TAP..6
R 2
(-3300 5400);
FORCEPROP 3 LASTPIN (-3350 5400) SIG_NAME P5E_CPU1_P2_TX_DN<2>
J 0
(-3340 5410);
DISPLAY 0.659574 (-3340 5410);
PAINT MONO (-3340 5410);
DISPLAY INVISIBLE (-3340 5410);
FORCEPROP 1 LASTPIN (-3350 5400) BN 2
J 2
(-3298 5408);
DISPLAY 0.489362 (-3298 5408);
PAINT MONO (-3298 5408);
FORCEPROP 2 LAST CDS_LIB standard
J 0
(-3300 5400);
DISPLAY INVISIBLE (-3300 5400);
FORCEPROP 2 LAST BOM_COST IO_SLOT
J 0
(-3800 5500);
DISPLAY 0.829787 (-3800 5500);
DISPLAY INVISIBLE (-3800 5500);
FORCEPROP 1 LAST BODY_TYPE PLUMBING
J 2
(-3300 5350);
DISPLAY 0.702128 (-3300 5350);
PAINT GREEN (-3300 5350);
DISPLAY INVISIBLE (-3300 5350);
FORCEPROP 1 LAST HDL_TAP TRUE
J 2
(-3625 5275);
DISPLAY 0.702128 (-3625 5275);
PAINT GREEN (-3625 5275);
DISPLAY INVISIBLE (-3625 5275);
FORCEPROP 1 LAST PATH I153
J 2
(-3298 5400);
DISPLAY 0.872340 (-3298 5400);
PAINT GREEN (-3298 5400);
DISPLAY INVISIBLE (-3298 5400);
FORCEPROP 2 LAST ROOM RISER1
J 0
(-3800 5450);
DISPLAY 0.829787 (-3800 5450);
PAINT RED (-3800 5450);
DISPLAY INVISIBLE (-3800 5450);
FORCEADD TAP..6
R 2
(-3300 5600);
FORCEPROP 3 LASTPIN (-3350 5600) SIG_NAME P5E_CPU1_P2_TX_DN<0>
J 0
(-3340 5610);
DISPLAY 0.659574 (-3340 5610);
PAINT MONO (-3340 5610);
DISPLAY INVISIBLE (-3340 5610);
FORCEPROP 1 LASTPIN (-3350 5600) BN 0
J 2
(-3298 5608);
DISPLAY 0.489362 (-3298 5608);
PAINT MONO (-3298 5608);
FORCEPROP 2 LAST BOM_COST IO_SLOT
J 0
(-3800 5700);
DISPLAY 0.829787 (-3800 5700);
DISPLAY INVISIBLE (-3800 5700);
FORCEPROP 2 LAST CDS_LIB mstr_standard
J 0
(-3300 5600);
DISPLAY INVISIBLE (-3300 5600);
FORCEPROP 1 LAST BODY_TYPE PLUMBING
J 2
(-3300 5550);
DISPLAY 0.702128 (-3300 5550);
PAINT GREEN (-3300 5550);
DISPLAY INVISIBLE (-3300 5550);
FORCEPROP 1 LAST HDL_TAP TRUE
J 2
(-3625 5475);
DISPLAY 0.702128 (-3625 5475);
PAINT GREEN (-3625 5475);
DISPLAY INVISIBLE (-3625 5475);
FORCEPROP 1 LAST PATH I154
J 2
(-3298 5600);
DISPLAY 0.872340 (-3298 5600);
PAINT GREEN (-3298 5600);
DISPLAY INVISIBLE (-3298 5600);
FORCEPROP 2 LAST ROOM RISER1
J 0
(-3800 5650);
DISPLAY 0.829787 (-3800 5650);
PAINT RED (-3800 5650);
DISPLAY INVISIBLE (-3800 5650);
FORCEADD TAP..6
R 2
(-3450 5550);
FORCEPROP 3 LASTPIN (-3500 5550) SIG_NAME P5E_CPU1_P2_TX_DP<1>
J 0
(-3490 5560);
DISPLAY 0.659574 (-3490 5560);
PAINT MONO (-3490 5560);
DISPLAY INVISIBLE (-3490 5560);
FORCEPROP 1 LASTPIN (-3500 5550) BN 1
J 2
(-3448 5558);
DISPLAY 0.489362 (-3448 5558);
PAINT MONO (-3448 5558);
FORCEPROP 2 LAST CDS_LIB mstr_standard
J 0
(-3450 5550);
DISPLAY INVISIBLE (-3450 5550);
FORCEPROP 2 LAST BOM_COST IO_SLOT
J 0
(-3950 5650);
DISPLAY 0.829787 (-3950 5650);
DISPLAY INVISIBLE (-3950 5650);
FORCEPROP 1 LAST BODY_TYPE PLUMBING
J 2
(-3450 5500);
DISPLAY 0.702128 (-3450 5500);
PAINT GREEN (-3450 5500);
DISPLAY INVISIBLE (-3450 5500);
FORCEPROP 1 LAST HDL_TAP TRUE
J 2
(-3775 5425);
DISPLAY 0.702128 (-3775 5425);
PAINT GREEN (-3775 5425);
DISPLAY INVISIBLE (-3775 5425);
FORCEPROP 1 LAST PATH I155
J 2
(-3448 5550);
DISPLAY 0.872340 (-3448 5550);
PAINT GREEN (-3448 5550);
DISPLAY INVISIBLE (-3448 5550);
FORCEPROP 2 LAST ROOM RISER1
J 0
(-3950 5600);
DISPLAY 0.829787 (-3950 5600);
PAINT RED (-3950 5600);
DISPLAY INVISIBLE (-3950 5600);
FORCEADD TAP..6
R 2
(-3450 5450);
FORCEPROP 3 LASTPIN (-3500 5450) SIG_NAME P5E_CPU1_P2_TX_DP<2>
J 0
(-3490 5460);
DISPLAY 0.659574 (-3490 5460);
PAINT MONO (-3490 5460);
DISPLAY INVISIBLE (-3490 5460);
FORCEPROP 1 LASTPIN (-3500 5450) BN 2
J 2
(-3448 5458);
DISPLAY 0.489362 (-3448 5458);
PAINT MONO (-3448 5458);
FORCEPROP 2 LAST CDS_LIB standard
J 0
(-3450 5450);
DISPLAY INVISIBLE (-3450 5450);
FORCEPROP 2 LAST BOM_COST IO_SLOT
J 0
(-3950 5550);
DISPLAY 0.829787 (-3950 5550);
DISPLAY INVISIBLE (-3950 5550);
FORCEPROP 1 LAST BODY_TYPE PLUMBING
J 2
(-3450 5400);
DISPLAY 0.702128 (-3450 5400);
PAINT GREEN (-3450 5400);
DISPLAY INVISIBLE (-3450 5400);
FORCEPROP 1 LAST HDL_TAP TRUE
J 2
(-3775 5325);
DISPLAY 0.702128 (-3775 5325);
PAINT GREEN (-3775 5325);
DISPLAY INVISIBLE (-3775 5325);
FORCEPROP 1 LAST PATH I156
J 2
(-3448 5450);
DISPLAY 0.872340 (-3448 5450);
PAINT GREEN (-3448 5450);
DISPLAY INVISIBLE (-3448 5450);
FORCEPROP 2 LAST ROOM RISER1
J 0
(-3950 5500);
DISPLAY 0.829787 (-3950 5500);
PAINT RED (-3950 5500);
DISPLAY INVISIBLE (-3950 5500);
FORCEADD TAP..6
R 2
(-3300 5300);
FORCEPROP 3 LASTPIN (-3350 5300) SIG_NAME P5E_CPU1_P2_TX_DN<3>
J 0
(-3340 5310);
DISPLAY 0.659574 (-3340 5310);
PAINT MONO (-3340 5310);
DISPLAY INVISIBLE (-3340 5310);
FORCEPROP 1 LASTPIN (-3350 5300) BN 3
J 2
(-3298 5308);
DISPLAY 0.489362 (-3298 5308);
PAINT MONO (-3298 5308);
FORCEPROP 2 LAST CDS_LIB standard
J 0
(-3300 5300);
DISPLAY INVISIBLE (-3300 5300);
FORCEPROP 2 LAST BOM_COST IO_SLOT
J 0
(-3800 5400);
DISPLAY 0.829787 (-3800 5400);
DISPLAY INVISIBLE (-3800 5400);
FORCEPROP 1 LAST BODY_TYPE PLUMBING
J 2
(-3300 5250);
DISPLAY 0.702128 (-3300 5250);
PAINT GREEN (-3300 5250);
DISPLAY INVISIBLE (-3300 5250);
FORCEPROP 1 LAST HDL_TAP TRUE
J 2
(-3625 5175);
DISPLAY 0.702128 (-3625 5175);
PAINT GREEN (-3625 5175);
DISPLAY INVISIBLE (-3625 5175);
FORCEPROP 1 LAST PATH I157
J 2
(-3298 5300);
DISPLAY 0.872340 (-3298 5300);
PAINT GREEN (-3298 5300);
DISPLAY INVISIBLE (-3298 5300);
FORCEPROP 2 LAST ROOM RISER1
J 0
(-3800 5350);
DISPLAY 0.829787 (-3800 5350);
PAINT RED (-3800 5350);
DISPLAY INVISIBLE (-3800 5350);
FORCEADD TAP..6
R 2
(-3300 5200);
FORCEPROP 3 LASTPIN (-3350 5200) SIG_NAME P5E_CPU1_P2_TX_DN<4>
J 0
(-3340 5210);
DISPLAY 0.659574 (-3340 5210);
PAINT MONO (-3340 5210);
DISPLAY INVISIBLE (-3340 5210);
FORCEPROP 1 LASTPIN (-3350 5200) BN 4
J 2
(-3298 5208);
DISPLAY 0.489362 (-3298 5208);
PAINT MONO (-3298 5208);
FORCEPROP 2 LAST CDS_LIB standard
J 0
(-3300 5200);
DISPLAY INVISIBLE (-3300 5200);
FORCEPROP 2 LAST BOM_COST IO_SLOT
J 0
(-3800 5300);
DISPLAY 0.829787 (-3800 5300);
DISPLAY INVISIBLE (-3800 5300);
FORCEPROP 1 LAST BODY_TYPE PLUMBING
J 2
(-3300 5150);
DISPLAY 0.702128 (-3300 5150);
PAINT GREEN (-3300 5150);
DISPLAY INVISIBLE (-3300 5150);
FORCEPROP 1 LAST HDL_TAP TRUE
J 2
(-3625 5075);
DISPLAY 0.702128 (-3625 5075);
PAINT GREEN (-3625 5075);
DISPLAY INVISIBLE (-3625 5075);
FORCEPROP 1 LAST PATH I158
J 2
(-3298 5200);
DISPLAY 0.872340 (-3298 5200);
PAINT GREEN (-3298 5200);
DISPLAY INVISIBLE (-3298 5200);
FORCEPROP 2 LAST ROOM RISER1
J 0
(-3800 5250);
DISPLAY 0.829787 (-3800 5250);
PAINT RED (-3800 5250);
DISPLAY INVISIBLE (-3800 5250);
FORCEADD TAP..6
R 2
(-3450 5250);
FORCEPROP 3 LASTPIN (-3500 5250) SIG_NAME P5E_CPU1_P2_TX_DP<4>
J 0
(-3490 5260);
DISPLAY 0.659574 (-3490 5260);
PAINT MONO (-3490 5260);
DISPLAY INVISIBLE (-3490 5260);
FORCEPROP 1 LASTPIN (-3500 5250) BN 4
J 2
(-3448 5258);
DISPLAY 0.489362 (-3448 5258);
PAINT MONO (-3448 5258);
FORCEPROP 2 LAST CDS_LIB standard
J 0
(-3450 5250);
DISPLAY INVISIBLE (-3450 5250);
FORCEPROP 2 LAST BOM_COST IO_SLOT
J 0
(-3950 5350);
DISPLAY 0.829787 (-3950 5350);
DISPLAY INVISIBLE (-3950 5350);
FORCEPROP 1 LAST BODY_TYPE PLUMBING
J 2
(-3450 5200);
DISPLAY 0.702128 (-3450 5200);
PAINT GREEN (-3450 5200);
DISPLAY INVISIBLE (-3450 5200);
FORCEPROP 1 LAST HDL_TAP TRUE
J 2
(-3775 5125);
DISPLAY 0.702128 (-3775 5125);
PAINT GREEN (-3775 5125);
DISPLAY INVISIBLE (-3775 5125);
FORCEPROP 1 LAST PATH I159
J 2
(-3448 5250);
DISPLAY 0.872340 (-3448 5250);
PAINT GREEN (-3448 5250);
DISPLAY INVISIBLE (-3448 5250);
FORCEPROP 2 LAST ROOM RISER1
J 0
(-3950 5300);
DISPLAY 0.829787 (-3950 5300);
PAINT RED (-3950 5300);
DISPLAY INVISIBLE (-3950 5300);
FORCEADD TAP..6
R 2
(-3450 5350);
FORCEPROP 3 LASTPIN (-3500 5350) SIG_NAME P5E_CPU1_P2_TX_DP<3>
J 0
(-3490 5360);
DISPLAY 0.659574 (-3490 5360);
PAINT MONO (-3490 5360);
DISPLAY INVISIBLE (-3490 5360);
FORCEPROP 1 LASTPIN (-3500 5350) BN 3
J 2
(-3448 5358);
DISPLAY 0.489362 (-3448 5358);
PAINT MONO (-3448 5358);
FORCEPROP 2 LAST CDS_LIB standard
J 0
(-3450 5350);
DISPLAY INVISIBLE (-3450 5350);
FORCEPROP 2 LAST BOM_COST IO_SLOT
J 0
(-3950 5450);
DISPLAY 0.829787 (-3950 5450);
DISPLAY INVISIBLE (-3950 5450);
FORCEPROP 1 LAST BODY_TYPE PLUMBING
J 2
(-3450 5300);
DISPLAY 0.702128 (-3450 5300);
PAINT GREEN (-3450 5300);
DISPLAY INVISIBLE (-3450 5300);
FORCEPROP 1 LAST HDL_TAP TRUE
J 2
(-3775 5225);
DISPLAY 0.702128 (-3775 5225);
PAINT GREEN (-3775 5225);
DISPLAY INVISIBLE (-3775 5225);
FORCEPROP 1 LAST PATH I160
J 2
(-3448 5350);
DISPLAY 0.872340 (-3448 5350);
PAINT GREEN (-3448 5350);
DISPLAY INVISIBLE (-3448 5350);
FORCEPROP 2 LAST ROOM RISER1
J 0
(-3950 5400);
DISPLAY 0.829787 (-3950 5400);
PAINT RED (-3950 5400);
DISPLAY INVISIBLE (-3950 5400);
FORCEADD TAP..6
R 2
(-3450 5150);
FORCEPROP 3 LASTPIN (-3500 5150) SIG_NAME P5E_CPU1_P2_TX_DP<5>
J 0
(-3490 5160);
DISPLAY 0.659574 (-3490 5160);
PAINT MONO (-3490 5160);
DISPLAY INVISIBLE (-3490 5160);
FORCEPROP 1 LASTPIN (-3500 5150) BN 5
J 2
(-3448 5158);
DISPLAY 0.489362 (-3448 5158);
PAINT MONO (-3448 5158);
FORCEPROP 2 LAST CDS_LIB standard
J 0
(-3450 5150);
DISPLAY INVISIBLE (-3450 5150);
FORCEPROP 2 LAST BOM_COST IO_SLOT
J 0
(-3950 5250);
DISPLAY 0.829787 (-3950 5250);
DISPLAY INVISIBLE (-3950 5250);
FORCEPROP 1 LAST BODY_TYPE PLUMBING
J 2
(-3450 5100);
DISPLAY 0.702128 (-3450 5100);
PAINT GREEN (-3450 5100);
DISPLAY INVISIBLE (-3450 5100);
FORCEPROP 1 LAST HDL_TAP TRUE
J 2
(-3775 5025);
DISPLAY 0.702128 (-3775 5025);
PAINT GREEN (-3775 5025);
DISPLAY INVISIBLE (-3775 5025);
FORCEPROP 1 LAST PATH I161
J 2
(-3448 5150);
DISPLAY 0.872340 (-3448 5150);
PAINT GREEN (-3448 5150);
DISPLAY INVISIBLE (-3448 5150);
FORCEPROP 2 LAST ROOM RISER1
J 0
(-3950 5200);
DISPLAY 0.829787 (-3950 5200);
PAINT RED (-3950 5200);
DISPLAY INVISIBLE (-3950 5200);
FORCEADD TAP..6
R 2
(-3300 5000);
FORCEPROP 3 LASTPIN (-3350 5000) SIG_NAME P5E_CPU1_P2_TX_DN<6>
J 0
(-3340 5010);
DISPLAY 0.659574 (-3340 5010);
PAINT MONO (-3340 5010);
DISPLAY INVISIBLE (-3340 5010);
FORCEPROP 1 LASTPIN (-3350 5000) BN 6
J 2
(-3298 5008);
DISPLAY 0.489362 (-3298 5008);
PAINT MONO (-3298 5008);
FORCEPROP 2 LAST CDS_LIB standard
J 0
(-3300 5000);
DISPLAY INVISIBLE (-3300 5000);
FORCEPROP 2 LAST BOM_COST IO_SLOT
J 0
(-3800 5100);
DISPLAY 0.829787 (-3800 5100);
DISPLAY INVISIBLE (-3800 5100);
FORCEPROP 1 LAST BODY_TYPE PLUMBING
J 2
(-3300 4950);
DISPLAY 0.702128 (-3300 4950);
PAINT GREEN (-3300 4950);
DISPLAY INVISIBLE (-3300 4950);
FORCEPROP 1 LAST HDL_TAP TRUE
J 2
(-3625 4875);
DISPLAY 0.702128 (-3625 4875);
PAINT GREEN (-3625 4875);
DISPLAY INVISIBLE (-3625 4875);
FORCEPROP 1 LAST PATH I162
J 2
(-3298 5000);
DISPLAY 0.872340 (-3298 5000);
PAINT GREEN (-3298 5000);
DISPLAY INVISIBLE (-3298 5000);
FORCEPROP 2 LAST ROOM RISER1
J 0
(-3800 5050);
DISPLAY 0.829787 (-3800 5050);
PAINT RED (-3800 5050);
DISPLAY INVISIBLE (-3800 5050);
FORCEADD TAP..6
R 2
(-3300 5100);
FORCEPROP 3 LASTPIN (-3350 5100) SIG_NAME P5E_CPU1_P2_TX_DN<5>
J 0
(-3340 5110);
DISPLAY 0.659574 (-3340 5110);
PAINT MONO (-3340 5110);
DISPLAY INVISIBLE (-3340 5110);
FORCEPROP 1 LASTPIN (-3350 5100) BN 5
J 2
(-3298 5108);
DISPLAY 0.489362 (-3298 5108);
PAINT MONO (-3298 5108);
FORCEPROP 2 LAST CDS_LIB standard
J 0
(-3300 5100);
DISPLAY INVISIBLE (-3300 5100);
FORCEPROP 2 LAST BOM_COST IO_SLOT
J 0
(-3800 5200);
DISPLAY 0.829787 (-3800 5200);
DISPLAY INVISIBLE (-3800 5200);
FORCEPROP 1 LAST BODY_TYPE PLUMBING
J 2
(-3300 5050);
DISPLAY 0.702128 (-3300 5050);
PAINT GREEN (-3300 5050);
DISPLAY INVISIBLE (-3300 5050);
FORCEPROP 1 LAST HDL_TAP TRUE
J 2
(-3625 4975);
DISPLAY 0.702128 (-3625 4975);
PAINT GREEN (-3625 4975);
DISPLAY INVISIBLE (-3625 4975);
FORCEPROP 1 LAST PATH I163
J 2
(-3298 5100);
DISPLAY 0.872340 (-3298 5100);
PAINT GREEN (-3298 5100);
DISPLAY INVISIBLE (-3298 5100);
FORCEPROP 2 LAST ROOM RISER1
J 0
(-3800 5150);
DISPLAY 0.829787 (-3800 5150);
PAINT RED (-3800 5150);
DISPLAY INVISIBLE (-3800 5150);
FORCEADD TAP..6
R 2
(-3300 4900);
FORCEPROP 3 LASTPIN (-3350 4900) SIG_NAME P5E_CPU1_P2_TX_DN<7>
J 0
(-3340 4910);
DISPLAY 0.659574 (-3340 4910);
PAINT MONO (-3340 4910);
DISPLAY INVISIBLE (-3340 4910);
FORCEPROP 1 LASTPIN (-3350 4900) BN 7
J 2
(-3298 4908);
DISPLAY 0.489362 (-3298 4908);
PAINT MONO (-3298 4908);
FORCEPROP 2 LAST CDS_LIB standard
J 0
(-3300 4900);
DISPLAY INVISIBLE (-3300 4900);
FORCEPROP 2 LAST BOM_COST IO_SLOT
J 0
(-3800 5000);
DISPLAY 0.829787 (-3800 5000);
DISPLAY INVISIBLE (-3800 5000);
FORCEPROP 1 LAST BODY_TYPE PLUMBING
J 2
(-3300 4850);
DISPLAY 0.702128 (-3300 4850);
PAINT GREEN (-3300 4850);
DISPLAY INVISIBLE (-3300 4850);
FORCEPROP 1 LAST HDL_TAP TRUE
J 2
(-3625 4775);
DISPLAY 0.702128 (-3625 4775);
PAINT GREEN (-3625 4775);
DISPLAY INVISIBLE (-3625 4775);
FORCEPROP 1 LAST PATH I164
J 2
(-3298 4900);
DISPLAY 0.872340 (-3298 4900);
PAINT GREEN (-3298 4900);
DISPLAY INVISIBLE (-3298 4900);
FORCEPROP 2 LAST ROOM RISER1
J 0
(-3800 4950);
DISPLAY 0.829787 (-3800 4950);
PAINT RED (-3800 4950);
DISPLAY INVISIBLE (-3800 4950);
FORCEADD TAP..6
R 2
(-3450 4950);
FORCEPROP 3 LASTPIN (-3500 4950) SIG_NAME P5E_CPU1_P2_TX_DP<7>
J 0
(-3490 4960);
DISPLAY 0.659574 (-3490 4960);
PAINT MONO (-3490 4960);
DISPLAY INVISIBLE (-3490 4960);
FORCEPROP 1 LASTPIN (-3500 4950) BN 7
J 2
(-3448 4958);
DISPLAY 0.489362 (-3448 4958);
PAINT MONO (-3448 4958);
FORCEPROP 2 LAST CDS_LIB standard
J 0
(-3450 4950);
DISPLAY INVISIBLE (-3450 4950);
FORCEPROP 2 LAST BOM_COST IO_SLOT
J 0
(-3950 5050);
DISPLAY 0.829787 (-3950 5050);
DISPLAY INVISIBLE (-3950 5050);
FORCEPROP 1 LAST BODY_TYPE PLUMBING
J 2
(-3450 4900);
DISPLAY 0.702128 (-3450 4900);
PAINT GREEN (-3450 4900);
DISPLAY INVISIBLE (-3450 4900);
FORCEPROP 1 LAST HDL_TAP TRUE
J 2
(-3775 4825);
DISPLAY 0.702128 (-3775 4825);
PAINT GREEN (-3775 4825);
DISPLAY INVISIBLE (-3775 4825);
FORCEPROP 1 LAST PATH I165
J 2
(-3448 4950);
DISPLAY 0.872340 (-3448 4950);
PAINT GREEN (-3448 4950);
DISPLAY INVISIBLE (-3448 4950);
FORCEPROP 2 LAST ROOM RISER1
J 0
(-3950 5000);
DISPLAY 0.829787 (-3950 5000);
PAINT RED (-3950 5000);
DISPLAY INVISIBLE (-3950 5000);
FORCEADD TAP..6
R 2
(-3450 5050);
FORCEPROP 3 LASTPIN (-3500 5050) SIG_NAME P5E_CPU1_P2_TX_DP<6>
J 0
(-3490 5060);
DISPLAY 0.659574 (-3490 5060);
PAINT MONO (-3490 5060);
DISPLAY INVISIBLE (-3490 5060);
FORCEPROP 1 LASTPIN (-3500 5050) BN 6
J 2
(-3448 5058);
DISPLAY 0.489362 (-3448 5058);
PAINT MONO (-3448 5058);
FORCEPROP 2 LAST CDS_LIB standard
J 0
(-3450 5050);
DISPLAY INVISIBLE (-3450 5050);
FORCEPROP 2 LAST BOM_COST IO_SLOT
J 0
(-3950 5150);
DISPLAY 0.829787 (-3950 5150);
DISPLAY INVISIBLE (-3950 5150);
FORCEPROP 1 LAST BODY_TYPE PLUMBING
J 2
(-3450 5000);
DISPLAY 0.702128 (-3450 5000);
PAINT GREEN (-3450 5000);
DISPLAY INVISIBLE (-3450 5000);
FORCEPROP 1 LAST HDL_TAP TRUE
J 2
(-3775 4925);
DISPLAY 0.702128 (-3775 4925);
PAINT GREEN (-3775 4925);
DISPLAY INVISIBLE (-3775 4925);
FORCEPROP 1 LAST PATH I166
J 2
(-3448 5050);
DISPLAY 0.872340 (-3448 5050);
PAINT GREEN (-3448 5050);
DISPLAY INVISIBLE (-3448 5050);
FORCEPROP 2 LAST ROOM RISER1
J 0
(-3950 5100);
DISPLAY 0.829787 (-3950 5100);
PAINT RED (-3950 5100);
DISPLAY INVISIBLE (-3950 5100);
FORCEADD TAP..6
R 2
(-3300 4700);
FORCEPROP 3 LASTPIN (-3350 4700) SIG_NAME P5E_CPU1_P2_TX_DN<9>
J 0
(-3340 4710);
DISPLAY 0.659574 (-3340 4710);
PAINT MONO (-3340 4710);
DISPLAY INVISIBLE (-3340 4710);
FORCEPROP 1 LASTPIN (-3350 4700) BN 9
J 2
(-3298 4708);
DISPLAY 0.489362 (-3298 4708);
PAINT MONO (-3298 4708);
FORCEPROP 2 LAST CDS_LIB standard
J 0
(-3300 4700);
DISPLAY INVISIBLE (-3300 4700);
FORCEPROP 2 LAST BOM_COST IO_SLOT
J 0
(-3800 4800);
DISPLAY 0.829787 (-3800 4800);
DISPLAY INVISIBLE (-3800 4800);
FORCEPROP 1 LAST BODY_TYPE PLUMBING
J 2
(-3300 4650);
DISPLAY 0.702128 (-3300 4650);
PAINT GREEN (-3300 4650);
DISPLAY INVISIBLE (-3300 4650);
FORCEPROP 1 LAST HDL_TAP TRUE
J 2
(-3625 4575);
DISPLAY 0.702128 (-3625 4575);
PAINT GREEN (-3625 4575);
DISPLAY INVISIBLE (-3625 4575);
FORCEPROP 1 LAST PATH I167
J 2
(-3298 4700);
DISPLAY 0.872340 (-3298 4700);
PAINT GREEN (-3298 4700);
DISPLAY INVISIBLE (-3298 4700);
FORCEPROP 2 LAST ROOM RISER1
J 0
(-3800 4750);
DISPLAY 0.829787 (-3800 4750);
PAINT RED (-3800 4750);
DISPLAY INVISIBLE (-3800 4750);
FORCEADD TAP..6
R 2
(-3300 4800);
FORCEPROP 3 LASTPIN (-3350 4800) SIG_NAME P5E_CPU1_P2_TX_DN<8>
J 0
(-3340 4810);
DISPLAY 0.659574 (-3340 4810);
PAINT MONO (-3340 4810);
DISPLAY INVISIBLE (-3340 4810);
FORCEPROP 1 LASTPIN (-3350 4800) BN 8
J 2
(-3298 4808);
DISPLAY 0.489362 (-3298 4808);
PAINT MONO (-3298 4808);
FORCEPROP 2 LAST CDS_LIB standard
J 0
(-3300 4800);
DISPLAY INVISIBLE (-3300 4800);
FORCEPROP 2 LAST BOM_COST IO_SLOT
J 0
(-3800 4900);
DISPLAY 0.829787 (-3800 4900);
DISPLAY INVISIBLE (-3800 4900);
FORCEPROP 1 LAST BODY_TYPE PLUMBING
J 2
(-3300 4750);
DISPLAY 0.702128 (-3300 4750);
PAINT GREEN (-3300 4750);
DISPLAY INVISIBLE (-3300 4750);
FORCEPROP 1 LAST HDL_TAP TRUE
J 2
(-3625 4675);
DISPLAY 0.702128 (-3625 4675);
PAINT GREEN (-3625 4675);
DISPLAY INVISIBLE (-3625 4675);
FORCEPROP 1 LAST PATH I168
J 2
(-3298 4800);
DISPLAY 0.872340 (-3298 4800);
PAINT GREEN (-3298 4800);
DISPLAY INVISIBLE (-3298 4800);
FORCEPROP 2 LAST ROOM RISER1
J 0
(-3800 4850);
DISPLAY 0.829787 (-3800 4850);
PAINT RED (-3800 4850);
DISPLAY INVISIBLE (-3800 4850);
FORCEADD TAP..6
R 2
(-3450 4850);
FORCEPROP 3 LASTPIN (-3500 4850) SIG_NAME P5E_CPU1_P2_TX_DP<8>
J 0
(-3490 4860);
DISPLAY 0.659574 (-3490 4860);
PAINT MONO (-3490 4860);
DISPLAY INVISIBLE (-3490 4860);
FORCEPROP 1 LASTPIN (-3500 4850) BN 8
J 2
(-3448 4858);
DISPLAY 0.489362 (-3448 4858);
PAINT MONO (-3448 4858);
FORCEPROP 2 LAST CDS_LIB standard
J 0
(-3450 4850);
DISPLAY INVISIBLE (-3450 4850);
FORCEPROP 2 LAST BOM_COST IO_SLOT
J 0
(-3950 4950);
DISPLAY 0.829787 (-3950 4950);
DISPLAY INVISIBLE (-3950 4950);
FORCEPROP 1 LAST BODY_TYPE PLUMBING
J 2
(-3450 4800);
DISPLAY 0.702128 (-3450 4800);
PAINT GREEN (-3450 4800);
DISPLAY INVISIBLE (-3450 4800);
FORCEPROP 1 LAST HDL_TAP TRUE
J 2
(-3775 4725);
DISPLAY 0.702128 (-3775 4725);
PAINT GREEN (-3775 4725);
DISPLAY INVISIBLE (-3775 4725);
FORCEPROP 1 LAST PATH I169
J 2
(-3448 4850);
DISPLAY 0.872340 (-3448 4850);
PAINT GREEN (-3448 4850);
DISPLAY INVISIBLE (-3448 4850);
FORCEPROP 2 LAST ROOM RISER1
J 0
(-3950 4900);
DISPLAY 0.829787 (-3950 4900);
PAINT RED (-3950 4900);
DISPLAY INVISIBLE (-3950 4900);
FORCEADD TAP..6
R 2
(-3450 4750);
FORCEPROP 3 LASTPIN (-3500 4750) SIG_NAME P5E_CPU1_P2_TX_DP<9>
J 0
(-3490 4760);
DISPLAY 0.659574 (-3490 4760);
PAINT MONO (-3490 4760);
DISPLAY INVISIBLE (-3490 4760);
FORCEPROP 1 LASTPIN (-3500 4750) BN 9
J 2
(-3448 4758);
DISPLAY 0.489362 (-3448 4758);
PAINT MONO (-3448 4758);
FORCEPROP 2 LAST CDS_LIB standard
J 0
(-3450 4750);
DISPLAY INVISIBLE (-3450 4750);
FORCEPROP 2 LAST BOM_COST IO_SLOT
J 0
(-3950 4850);
DISPLAY 0.829787 (-3950 4850);
DISPLAY INVISIBLE (-3950 4850);
FORCEPROP 1 LAST BODY_TYPE PLUMBING
J 2
(-3450 4700);
DISPLAY 0.702128 (-3450 4700);
PAINT GREEN (-3450 4700);
DISPLAY INVISIBLE (-3450 4700);
FORCEPROP 1 LAST HDL_TAP TRUE
J 2
(-3775 4625);
DISPLAY 0.702128 (-3775 4625);
PAINT GREEN (-3775 4625);
DISPLAY INVISIBLE (-3775 4625);
FORCEPROP 1 LAST PATH I170
J 2
(-3448 4750);
DISPLAY 0.872340 (-3448 4750);
PAINT GREEN (-3448 4750);
DISPLAY INVISIBLE (-3448 4750);
FORCEPROP 2 LAST ROOM RISER1
J 0
(-3950 4800);
DISPLAY 0.829787 (-3950 4800);
PAINT RED (-3950 4800);
DISPLAY INVISIBLE (-3950 4800);
FORCEADD TAP..6
R 2
(-3450 4650);
FORCEPROP 3 LASTPIN (-3500 4650) SIG_NAME P5E_CPU1_P2_TX_DP<10>
J 0
(-3490 4660);
DISPLAY 0.659574 (-3490 4660);
PAINT MONO (-3490 4660);
DISPLAY INVISIBLE (-3490 4660);
FORCEPROP 1 LASTPIN (-3500 4650) BN 10
J 2
(-3448 4658);
DISPLAY 0.489362 (-3448 4658);
PAINT MONO (-3448 4658);
FORCEPROP 2 LAST CDS_LIB standard
J 0
(-3450 4650);
DISPLAY INVISIBLE (-3450 4650);
FORCEPROP 2 LAST BOM_COST IO_SLOT
J 0
(-3950 4750);
DISPLAY 0.829787 (-3950 4750);
DISPLAY INVISIBLE (-3950 4750);
FORCEPROP 1 LAST BODY_TYPE PLUMBING
J 2
(-3450 4600);
DISPLAY 0.702128 (-3450 4600);
PAINT GREEN (-3450 4600);
DISPLAY INVISIBLE (-3450 4600);
FORCEPROP 1 LAST HDL_TAP TRUE
J 2
(-3775 4525);
DISPLAY 0.702128 (-3775 4525);
PAINT GREEN (-3775 4525);
DISPLAY INVISIBLE (-3775 4525);
FORCEPROP 1 LAST PATH I171
J 2
(-3448 4650);
DISPLAY 0.872340 (-3448 4650);
PAINT GREEN (-3448 4650);
DISPLAY INVISIBLE (-3448 4650);
FORCEPROP 2 LAST ROOM RISER1
J 0
(-3950 4700);
DISPLAY 0.829787 (-3950 4700);
PAINT RED (-3950 4700);
DISPLAY INVISIBLE (-3950 4700);
FORCEADD TAP..6
R 2
(-3300 4600);
FORCEPROP 3 LASTPIN (-3350 4600) SIG_NAME P5E_CPU1_P2_TX_DN<10>
J 0
(-3340 4610);
DISPLAY 0.659574 (-3340 4610);
PAINT MONO (-3340 4610);
DISPLAY INVISIBLE (-3340 4610);
FORCEPROP 1 LASTPIN (-3350 4600) BN 10
J 2
(-3298 4608);
DISPLAY 0.489362 (-3298 4608);
PAINT MONO (-3298 4608);
FORCEPROP 2 LAST CDS_LIB standard
J 0
(-3300 4600);
DISPLAY INVISIBLE (-3300 4600);
FORCEPROP 2 LAST BOM_COST IO_SLOT
J 0
(-3800 4700);
DISPLAY 0.829787 (-3800 4700);
DISPLAY INVISIBLE (-3800 4700);
FORCEPROP 1 LAST BODY_TYPE PLUMBING
J 2
(-3300 4550);
DISPLAY 0.702128 (-3300 4550);
PAINT GREEN (-3300 4550);
DISPLAY INVISIBLE (-3300 4550);
FORCEPROP 1 LAST HDL_TAP TRUE
J 2
(-3625 4475);
DISPLAY 0.702128 (-3625 4475);
PAINT GREEN (-3625 4475);
DISPLAY INVISIBLE (-3625 4475);
FORCEPROP 1 LAST PATH I172
J 2
(-3298 4600);
DISPLAY 0.872340 (-3298 4600);
PAINT GREEN (-3298 4600);
DISPLAY INVISIBLE (-3298 4600);
FORCEPROP 2 LAST ROOM RISER1
J 0
(-3800 4650);
DISPLAY 0.829787 (-3800 4650);
PAINT RED (-3800 4650);
DISPLAY INVISIBLE (-3800 4650);
FORCEADD TAP..6
R 2
(-3300 4500);
FORCEPROP 3 LASTPIN (-3350 4500) SIG_NAME P5E_CPU1_P2_TX_DN<11>
J 0
(-3340 4510);
DISPLAY 0.659574 (-3340 4510);
PAINT MONO (-3340 4510);
DISPLAY INVISIBLE (-3340 4510);
FORCEPROP 1 LASTPIN (-3350 4500) BN 11
J 2
(-3298 4508);
DISPLAY 0.489362 (-3298 4508);
PAINT MONO (-3298 4508);
FORCEPROP 2 LAST CDS_LIB standard
J 0
(-3300 4500);
DISPLAY INVISIBLE (-3300 4500);
FORCEPROP 2 LAST BOM_COST IO_SLOT
J 0
(-3800 4600);
DISPLAY 0.829787 (-3800 4600);
DISPLAY INVISIBLE (-3800 4600);
FORCEPROP 1 LAST BODY_TYPE PLUMBING
J 2
(-3300 4450);
DISPLAY 0.702128 (-3300 4450);
PAINT GREEN (-3300 4450);
DISPLAY INVISIBLE (-3300 4450);
FORCEPROP 1 LAST HDL_TAP TRUE
J 2
(-3625 4375);
DISPLAY 0.702128 (-3625 4375);
PAINT GREEN (-3625 4375);
DISPLAY INVISIBLE (-3625 4375);
FORCEPROP 1 LAST PATH I173
J 2
(-3298 4500);
DISPLAY 0.872340 (-3298 4500);
PAINT GREEN (-3298 4500);
DISPLAY INVISIBLE (-3298 4500);
FORCEPROP 2 LAST ROOM RISER1
J 0
(-3800 4550);
DISPLAY 0.829787 (-3800 4550);
PAINT RED (-3800 4550);
DISPLAY INVISIBLE (-3800 4550);
FORCEADD TAP..6
R 2
(-3300 4400);
FORCEPROP 3 LASTPIN (-3350 4400) SIG_NAME P5E_CPU1_P2_TX_DN<12>
J 0
(-3340 4410);
DISPLAY 0.659574 (-3340 4410);
PAINT MONO (-3340 4410);
DISPLAY INVISIBLE (-3340 4410);
FORCEPROP 1 LASTPIN (-3350 4400) BN 12
J 2
(-3298 4408);
DISPLAY 0.489362 (-3298 4408);
PAINT MONO (-3298 4408);
FORCEPROP 2 LAST CDS_LIB standard
J 0
(-3300 4400);
DISPLAY INVISIBLE (-3300 4400);
FORCEPROP 2 LAST BOM_COST IO_SLOT
J 0
(-3800 4500);
DISPLAY 0.829787 (-3800 4500);
DISPLAY INVISIBLE (-3800 4500);
FORCEPROP 1 LAST BODY_TYPE PLUMBING
J 2
(-3300 4350);
DISPLAY 0.702128 (-3300 4350);
PAINT GREEN (-3300 4350);
DISPLAY INVISIBLE (-3300 4350);
FORCEPROP 1 LAST HDL_TAP TRUE
J 2
(-3625 4275);
DISPLAY 0.702128 (-3625 4275);
PAINT GREEN (-3625 4275);
DISPLAY INVISIBLE (-3625 4275);
FORCEPROP 1 LAST PATH I174
J 2
(-3298 4400);
DISPLAY 0.872340 (-3298 4400);
PAINT GREEN (-3298 4400);
DISPLAY INVISIBLE (-3298 4400);
FORCEPROP 2 LAST ROOM RISER1
J 0
(-3800 4450);
DISPLAY 0.829787 (-3800 4450);
PAINT RED (-3800 4450);
DISPLAY INVISIBLE (-3800 4450);
FORCEADD TAP..6
R 2
(-3450 4550);
FORCEPROP 3 LASTPIN (-3500 4550) SIG_NAME P5E_CPU1_P2_TX_DP<11>
J 0
(-3490 4560);
DISPLAY 0.659574 (-3490 4560);
PAINT MONO (-3490 4560);
DISPLAY INVISIBLE (-3490 4560);
FORCEPROP 1 LASTPIN (-3500 4550) BN 11
J 2
(-3448 4558);
DISPLAY 0.489362 (-3448 4558);
PAINT MONO (-3448 4558);
FORCEPROP 2 LAST CDS_LIB standard
J 0
(-3450 4550);
DISPLAY INVISIBLE (-3450 4550);
FORCEPROP 2 LAST BOM_COST IO_SLOT
J 0
(-3950 4650);
DISPLAY 0.829787 (-3950 4650);
DISPLAY INVISIBLE (-3950 4650);
FORCEPROP 1 LAST BODY_TYPE PLUMBING
J 2
(-3450 4500);
DISPLAY 0.702128 (-3450 4500);
PAINT GREEN (-3450 4500);
DISPLAY INVISIBLE (-3450 4500);
FORCEPROP 1 LAST HDL_TAP TRUE
J 2
(-3775 4425);
DISPLAY 0.702128 (-3775 4425);
PAINT GREEN (-3775 4425);
DISPLAY INVISIBLE (-3775 4425);
FORCEPROP 1 LAST PATH I175
J 2
(-3448 4550);
DISPLAY 0.872340 (-3448 4550);
PAINT GREEN (-3448 4550);
DISPLAY INVISIBLE (-3448 4550);
FORCEPROP 2 LAST ROOM RISER1
J 0
(-3950 4600);
DISPLAY 0.829787 (-3950 4600);
PAINT RED (-3950 4600);
DISPLAY INVISIBLE (-3950 4600);
FORCEADD TAP..6
R 2
(-3450 4450);
FORCEPROP 3 LASTPIN (-3500 4450) SIG_NAME P5E_CPU1_P2_TX_DP<12>
J 0
(-3490 4460);
DISPLAY 0.659574 (-3490 4460);
PAINT MONO (-3490 4460);
DISPLAY INVISIBLE (-3490 4460);
FORCEPROP 1 LASTPIN (-3500 4450) BN 12
J 2
(-3448 4458);
DISPLAY 0.489362 (-3448 4458);
PAINT MONO (-3448 4458);
FORCEPROP 2 LAST CDS_LIB standard
J 0
(-3450 4450);
DISPLAY INVISIBLE (-3450 4450);
FORCEPROP 2 LAST BOM_COST IO_SLOT
J 0
(-3950 4550);
DISPLAY 0.829787 (-3950 4550);
DISPLAY INVISIBLE (-3950 4550);
FORCEPROP 1 LAST BODY_TYPE PLUMBING
J 2
(-3450 4400);
DISPLAY 0.702128 (-3450 4400);
PAINT GREEN (-3450 4400);
DISPLAY INVISIBLE (-3450 4400);
FORCEPROP 1 LAST HDL_TAP TRUE
J 2
(-3775 4325);
DISPLAY 0.702128 (-3775 4325);
PAINT GREEN (-3775 4325);
DISPLAY INVISIBLE (-3775 4325);
FORCEPROP 1 LAST PATH I176
J 2
(-3448 4450);
DISPLAY 0.872340 (-3448 4450);
PAINT GREEN (-3448 4450);
DISPLAY INVISIBLE (-3448 4450);
FORCEPROP 2 LAST ROOM RISER1
J 0
(-3950 4500);
DISPLAY 0.829787 (-3950 4500);
PAINT RED (-3950 4500);
DISPLAY INVISIBLE (-3950 4500);
FORCEADD TAP..6
R 2
(-3300 4200);
FORCEPROP 3 LASTPIN (-3350 4200) SIG_NAME P5E_CPU1_P2_TX_DN<14>
J 0
(-3340 4210);
DISPLAY 0.659574 (-3340 4210);
PAINT MONO (-3340 4210);
DISPLAY INVISIBLE (-3340 4210);
FORCEPROP 1 LASTPIN (-3350 4200) BN 14
J 2
(-3298 4208);
DISPLAY 0.489362 (-3298 4208);
PAINT MONO (-3298 4208);
FORCEPROP 2 LAST BOM_COST IO_SLOT
J 0
(-3800 4300);
DISPLAY 0.829787 (-3800 4300);
DISPLAY INVISIBLE (-3800 4300);
FORCEPROP 2 LAST CDS_LIB standard
J 0
(-3300 4200);
DISPLAY INVISIBLE (-3300 4200);
FORCEPROP 1 LAST BODY_TYPE PLUMBING
J 2
(-3300 4150);
DISPLAY 0.702128 (-3300 4150);
PAINT GREEN (-3300 4150);
DISPLAY INVISIBLE (-3300 4150);
FORCEPROP 1 LAST HDL_TAP TRUE
J 2
(-3625 4075);
DISPLAY 0.702128 (-3625 4075);
PAINT GREEN (-3625 4075);
DISPLAY INVISIBLE (-3625 4075);
FORCEPROP 1 LAST PATH I177
J 2
(-3298 4200);
DISPLAY 0.872340 (-3298 4200);
PAINT GREEN (-3298 4200);
DISPLAY INVISIBLE (-3298 4200);
FORCEPROP 2 LAST ROOM RISER1
J 0
(-3800 4250);
DISPLAY 0.829787 (-3800 4250);
PAINT RED (-3800 4250);
DISPLAY INVISIBLE (-3800 4250);
FORCEADD TAP..6
R 2
(-3300 4100);
FORCEPROP 3 LASTPIN (-3350 4100) SIG_NAME P5E_CPU1_P2_TX_DN<15>
J 0
(-3340 4110);
DISPLAY 0.659574 (-3340 4110);
PAINT MONO (-3340 4110);
DISPLAY INVISIBLE (-3340 4110);
FORCEPROP 1 LASTPIN (-3350 4100) BN 15
J 2
(-3298 4108);
DISPLAY 0.489362 (-3298 4108);
PAINT MONO (-3298 4108);
FORCEPROP 2 LAST CDS_LIB standard
J 0
(-3300 4100);
DISPLAY INVISIBLE (-3300 4100);
FORCEPROP 2 LAST BOM_COST IO_SLOT
J 0
(-3800 4200);
DISPLAY 0.829787 (-3800 4200);
DISPLAY INVISIBLE (-3800 4200);
FORCEPROP 1 LAST BODY_TYPE PLUMBING
J 2
(-3300 4050);
DISPLAY 0.702128 (-3300 4050);
PAINT GREEN (-3300 4050);
DISPLAY INVISIBLE (-3300 4050);
FORCEPROP 1 LAST HDL_TAP TRUE
J 2
(-3625 3975);
DISPLAY 0.702128 (-3625 3975);
PAINT GREEN (-3625 3975);
DISPLAY INVISIBLE (-3625 3975);
FORCEPROP 1 LAST PATH I178
J 2
(-3298 4100);
DISPLAY 0.872340 (-3298 4100);
PAINT GREEN (-3298 4100);
DISPLAY INVISIBLE (-3298 4100);
FORCEPROP 2 LAST ROOM RISER1
J 0
(-3800 4150);
DISPLAY 0.829787 (-3800 4150);
PAINT RED (-3800 4150);
DISPLAY INVISIBLE (-3800 4150);
FORCEADD TAP..6
R 2
(-3300 4300);
FORCEPROP 3 LASTPIN (-3350 4300) SIG_NAME P5E_CPU1_P2_TX_DN<13>
J 0
(-3340 4310);
DISPLAY 0.659574 (-3340 4310);
PAINT MONO (-3340 4310);
DISPLAY INVISIBLE (-3340 4310);
FORCEPROP 1 LASTPIN (-3350 4300) BN 13
J 2
(-3298 4308);
DISPLAY 0.489362 (-3298 4308);
PAINT MONO (-3298 4308);
FORCEPROP 2 LAST CDS_LIB standard
J 0
(-3300 4300);
DISPLAY INVISIBLE (-3300 4300);
FORCEPROP 2 LAST BOM_COST IO_SLOT
J 0
(-3800 4400);
DISPLAY 0.829787 (-3800 4400);
DISPLAY INVISIBLE (-3800 4400);
FORCEPROP 1 LAST BODY_TYPE PLUMBING
J 2
(-3300 4250);
DISPLAY 0.702128 (-3300 4250);
PAINT GREEN (-3300 4250);
DISPLAY INVISIBLE (-3300 4250);
FORCEPROP 1 LAST HDL_TAP TRUE
J 2
(-3625 4175);
DISPLAY 0.702128 (-3625 4175);
PAINT GREEN (-3625 4175);
DISPLAY INVISIBLE (-3625 4175);
FORCEPROP 1 LAST PATH I179
J 2
(-3298 4300);
DISPLAY 0.872340 (-3298 4300);
PAINT GREEN (-3298 4300);
DISPLAY INVISIBLE (-3298 4300);
FORCEPROP 2 LAST ROOM RISER1
J 0
(-3800 4350);
DISPLAY 0.829787 (-3800 4350);
PAINT RED (-3800 4350);
DISPLAY INVISIBLE (-3800 4350);
FORCEADD TAP..6
R 2
(-3450 4350);
FORCEPROP 3 LASTPIN (-3500 4350) SIG_NAME P5E_CPU1_P2_TX_DP<13>
J 0
(-3490 4360);
DISPLAY 0.659574 (-3490 4360);
PAINT MONO (-3490 4360);
DISPLAY INVISIBLE (-3490 4360);
FORCEPROP 1 LASTPIN (-3500 4350) BN 13
J 2
(-3448 4358);
DISPLAY 0.489362 (-3448 4358);
PAINT MONO (-3448 4358);
FORCEPROP 2 LAST CDS_LIB standard
J 0
(-3450 4350);
DISPLAY INVISIBLE (-3450 4350);
FORCEPROP 2 LAST BOM_COST IO_SLOT
J 0
(-3950 4450);
DISPLAY 0.829787 (-3950 4450);
DISPLAY INVISIBLE (-3950 4450);
FORCEPROP 1 LAST BODY_TYPE PLUMBING
J 2
(-3450 4300);
DISPLAY 0.702128 (-3450 4300);
PAINT GREEN (-3450 4300);
DISPLAY INVISIBLE (-3450 4300);
FORCEPROP 1 LAST HDL_TAP TRUE
J 2
(-3775 4225);
DISPLAY 0.702128 (-3775 4225);
PAINT GREEN (-3775 4225);
DISPLAY INVISIBLE (-3775 4225);
FORCEPROP 1 LAST PATH I180
J 2
(-3448 4350);
DISPLAY 0.872340 (-3448 4350);
PAINT GREEN (-3448 4350);
DISPLAY INVISIBLE (-3448 4350);
FORCEPROP 2 LAST ROOM RISER1
J 0
(-3950 4400);
DISPLAY 0.829787 (-3950 4400);
PAINT RED (-3950 4400);
DISPLAY INVISIBLE (-3950 4400);
FORCEADD TAP..6
R 2
(-3450 4250);
FORCEPROP 3 LASTPIN (-3500 4250) SIG_NAME P5E_CPU1_P2_TX_DP<14>
J 0
(-3490 4260);
DISPLAY 0.659574 (-3490 4260);
PAINT MONO (-3490 4260);
DISPLAY INVISIBLE (-3490 4260);
FORCEPROP 1 LASTPIN (-3500 4250) BN 14
J 2
(-3448 4258);
DISPLAY 0.489362 (-3448 4258);
PAINT MONO (-3448 4258);
FORCEPROP 2 LAST CDS_LIB standard
J 0
(-3450 4250);
DISPLAY INVISIBLE (-3450 4250);
FORCEPROP 2 LAST BOM_COST IO_SLOT
J 0
(-3950 4350);
DISPLAY 0.829787 (-3950 4350);
DISPLAY INVISIBLE (-3950 4350);
FORCEPROP 1 LAST BODY_TYPE PLUMBING
J 2
(-3450 4200);
DISPLAY 0.702128 (-3450 4200);
PAINT GREEN (-3450 4200);
DISPLAY INVISIBLE (-3450 4200);
FORCEPROP 1 LAST HDL_TAP TRUE
J 2
(-3775 4125);
DISPLAY 0.702128 (-3775 4125);
PAINT GREEN (-3775 4125);
DISPLAY INVISIBLE (-3775 4125);
FORCEPROP 1 LAST PATH I181
J 2
(-3448 4250);
DISPLAY 0.872340 (-3448 4250);
PAINT GREEN (-3448 4250);
DISPLAY INVISIBLE (-3448 4250);
FORCEPROP 2 LAST ROOM RISER1
J 0
(-3950 4300);
DISPLAY 0.829787 (-3950 4300);
PAINT RED (-3950 4300);
DISPLAY INVISIBLE (-3950 4300);
FORCEADD TAP..6
R 2
(-3450 4150);
FORCEPROP 3 LASTPIN (-3500 4150) SIG_NAME P5E_CPU1_P2_TX_DP<15>
J 0
(-3490 4160);
DISPLAY 0.659574 (-3490 4160);
PAINT MONO (-3490 4160);
DISPLAY INVISIBLE (-3490 4160);
FORCEPROP 1 LASTPIN (-3500 4150) BN 15
J 2
(-3448 4158);
DISPLAY 0.489362 (-3448 4158);
PAINT MONO (-3448 4158);
FORCEPROP 2 LAST CDS_LIB standard
J 0
(-3450 4150);
DISPLAY INVISIBLE (-3450 4150);
FORCEPROP 2 LAST BOM_COST IO_SLOT
J 0
(-3950 4250);
DISPLAY 0.829787 (-3950 4250);
DISPLAY INVISIBLE (-3950 4250);
FORCEPROP 1 LAST BODY_TYPE PLUMBING
J 2
(-3450 4100);
DISPLAY 0.702128 (-3450 4100);
PAINT GREEN (-3450 4100);
DISPLAY INVISIBLE (-3450 4100);
FORCEPROP 1 LAST HDL_TAP TRUE
J 2
(-3775 4025);
DISPLAY 0.702128 (-3775 4025);
PAINT GREEN (-3775 4025);
DISPLAY INVISIBLE (-3775 4025);
FORCEPROP 1 LAST PATH I182
J 2
(-3448 4150);
DISPLAY 0.872340 (-3448 4150);
PAINT GREEN (-3448 4150);
DISPLAY INVISIBLE (-3448 4150);
FORCEPROP 2 LAST ROOM RISER1
J 0
(-3950 4200);
DISPLAY 0.829787 (-3950 4200);
PAINT RED (-3950 4200);
DISPLAY INVISIBLE (-3950 4200);
FORCEADD OFFPAGE..2
(-2325 3375);
FORCEPROP 2 LAST $XR0 66 
J 0
(-2136 3375);
DISPLAY 0.638298 (-2136 3375);
PAINT MONO (-2136 3375);
FORCEPROP 2 LAST PATH I183
J 0
(-2025 3425);
DISPLAY 1.021277 (-2025 3425);
DISPLAY INVISIBLE (-2025 3425);
FORCEPROP 1 LAST COMMENT_BODY TRUE
J 0
(-2370 3280);
DISPLAY 0.872340 (-2370 3280);
PAINT GREEN (-2370 3280);
DISPLAY INVISIBLE (-2370 3280);
FORCEPROP 1 LAST OFFPAGE TRUE
J 0
(-2000 3250);
DISPLAY 0.872340 (-2000 3250);
PAINT GREEN (-2000 3250);
DISPLAY INVISIBLE (-2000 3250);
FORCEPROP 2 LAST CDS_LIB standard
J 0
(-2325 3375);
DISPLAY INVISIBLE (-2325 3375);
FORCEADD OFFPAGE..2
(-2325 3325);
FORCEPROP 2 LAST $XR0 66 
J 0
(-2136 3325);
DISPLAY 0.638298 (-2136 3325);
PAINT MONO (-2136 3325);
FORCEPROP 2 LAST PATH I184
J 0
(-2025 3375);
DISPLAY 1.021277 (-2025 3375);
DISPLAY INVISIBLE (-2025 3375);
FORCEPROP 1 LAST COMMENT_BODY TRUE
J 0
(-2370 3230);
DISPLAY 0.872340 (-2370 3230);
PAINT GREEN (-2370 3230);
DISPLAY INVISIBLE (-2370 3230);
FORCEPROP 1 LAST OFFPAGE TRUE
J 0
(-2000 3200);
DISPLAY 0.872340 (-2000 3200);
PAINT GREEN (-2000 3200);
DISPLAY INVISIBLE (-2000 3200);
FORCEPROP 2 LAST CDS_LIB standard
J 0
(-2325 3325);
DISPLAY INVISIBLE (-2325 3325);
FORCEADD TAP..6
R 2
(-3300 3100);
FORCEPROP 3 LASTPIN (-3350 3100) SIG_NAME P5E_CPU1_P3_TX_DP<0>
J 0
(-3340 3110);
DISPLAY 0.659574 (-3340 3110);
PAINT MONO (-3340 3110);
DISPLAY INVISIBLE (-3340 3110);
FORCEPROP 1 LASTPIN (-3350 3100) BN 0
J 2
(-3298 3108);
DISPLAY 0.489362 (-3298 3108);
PAINT MONO (-3298 3108);
FORCEPROP 2 LAST CDS_LIB mstr_standard
J 0
(-3300 3100);
DISPLAY INVISIBLE (-3300 3100);
FORCEPROP 2 LAST BOM_COST IO_SLOT
J 0
(-3800 3200);
DISPLAY 0.829787 (-3800 3200);
DISPLAY INVISIBLE (-3800 3200);
FORCEPROP 1 LAST BODY_TYPE PLUMBING
J 2
(-3300 3050);
DISPLAY 0.702128 (-3300 3050);
PAINT GREEN (-3300 3050);
DISPLAY INVISIBLE (-3300 3050);
FORCEPROP 1 LAST HDL_TAP TRUE
J 2
(-3625 2975);
DISPLAY 0.702128 (-3625 2975);
PAINT GREEN (-3625 2975);
DISPLAY INVISIBLE (-3625 2975);
FORCEPROP 1 LAST PATH I185
J 2
(-3298 3100);
DISPLAY 0.872340 (-3298 3100);
PAINT GREEN (-3298 3100);
DISPLAY INVISIBLE (-3298 3100);
FORCEPROP 2 LAST ROOM RISER1
J 0
(-3800 3150);
DISPLAY 0.829787 (-3800 3150);
PAINT RED (-3800 3150);
DISPLAY INVISIBLE (-3800 3150);
FORCEADD TAP..6
R 2
(-3450 3150);
FORCEPROP 3 LASTPIN (-3500 3150) SIG_NAME P5E_CPU1_P3_TX_DN<0>
J 0
(-3490 3160);
DISPLAY 0.659574 (-3490 3160);
PAINT MONO (-3490 3160);
DISPLAY INVISIBLE (-3490 3160);
FORCEPROP 1 LASTPIN (-3500 3150) BN 0
J 2
(-3448 3158);
DISPLAY 0.489362 (-3448 3158);
PAINT MONO (-3448 3158);
FORCEPROP 2 LAST BOM_COST IO_SLOT
J 0
(-3950 3250);
DISPLAY 0.829787 (-3950 3250);
DISPLAY INVISIBLE (-3950 3250);
FORCEPROP 2 LAST CDS_LIB mstr_standard
J 0
(-3450 3150);
DISPLAY INVISIBLE (-3450 3150);
FORCEPROP 1 LAST BODY_TYPE PLUMBING
J 2
(-3450 3100);
DISPLAY 0.702128 (-3450 3100);
PAINT GREEN (-3450 3100);
DISPLAY INVISIBLE (-3450 3100);
FORCEPROP 1 LAST HDL_TAP TRUE
J 2
(-3775 3025);
DISPLAY 0.702128 (-3775 3025);
PAINT GREEN (-3775 3025);
DISPLAY INVISIBLE (-3775 3025);
FORCEPROP 1 LAST PATH I186
J 2
(-3448 3150);
DISPLAY 0.872340 (-3448 3150);
PAINT GREEN (-3448 3150);
DISPLAY INVISIBLE (-3448 3150);
FORCEPROP 2 LAST ROOM RISER1
J 0
(-3950 3200);
DISPLAY 0.829787 (-3950 3200);
PAINT RED (-3950 3200);
DISPLAY INVISIBLE (-3950 3200);
FORCEADD TAP..6
R 2
(-3300 2900);
FORCEPROP 3 LASTPIN (-3350 2900) SIG_NAME P5E_CPU1_P3_TX_DP<2>
J 0
(-3340 2910);
DISPLAY 0.659574 (-3340 2910);
PAINT MONO (-3340 2910);
DISPLAY INVISIBLE (-3340 2910);
FORCEPROP 1 LASTPIN (-3350 2900) BN 2
J 2
(-3298 2908);
DISPLAY 0.489362 (-3298 2908);
PAINT MONO (-3298 2908);
FORCEPROP 2 LAST BOM_COST IO_SLOT
J 0
(-3800 3000);
DISPLAY 0.829787 (-3800 3000);
DISPLAY INVISIBLE (-3800 3000);
FORCEPROP 2 LAST CDS_LIB standard
J 0
(-3300 2900);
DISPLAY INVISIBLE (-3300 2900);
FORCEPROP 1 LAST BODY_TYPE PLUMBING
J 2
(-3300 2850);
DISPLAY 0.702128 (-3300 2850);
PAINT GREEN (-3300 2850);
DISPLAY INVISIBLE (-3300 2850);
FORCEPROP 1 LAST HDL_TAP TRUE
J 2
(-3625 2775);
DISPLAY 0.702128 (-3625 2775);
PAINT GREEN (-3625 2775);
DISPLAY INVISIBLE (-3625 2775);
FORCEPROP 1 LAST PATH I187
J 2
(-3298 2900);
DISPLAY 0.872340 (-3298 2900);
PAINT GREEN (-3298 2900);
DISPLAY INVISIBLE (-3298 2900);
FORCEPROP 2 LAST ROOM RISER1
J 0
(-3800 2950);
DISPLAY 0.829787 (-3800 2950);
PAINT RED (-3800 2950);
DISPLAY INVISIBLE (-3800 2950);
FORCEADD TAP..6
R 2
(-3300 3000);
FORCEPROP 3 LASTPIN (-3350 3000) SIG_NAME P5E_CPU1_P3_TX_DP<1>
J 0
(-3340 3010);
DISPLAY 0.659574 (-3340 3010);
PAINT MONO (-3340 3010);
DISPLAY INVISIBLE (-3340 3010);
FORCEPROP 1 LASTPIN (-3350 3000) BN 1
J 2
(-3298 3008);
DISPLAY 0.489362 (-3298 3008);
PAINT MONO (-3298 3008);
FORCEPROP 2 LAST BOM_COST IO_SLOT
J 0
(-3800 3100);
DISPLAY 0.829787 (-3800 3100);
DISPLAY INVISIBLE (-3800 3100);
FORCEPROP 2 LAST CDS_LIB mstr_standard
J 0
(-3300 3000);
DISPLAY INVISIBLE (-3300 3000);
FORCEPROP 1 LAST BODY_TYPE PLUMBING
J 2
(-3300 2950);
DISPLAY 0.702128 (-3300 2950);
PAINT GREEN (-3300 2950);
DISPLAY INVISIBLE (-3300 2950);
FORCEPROP 1 LAST HDL_TAP TRUE
J 2
(-3625 2875);
DISPLAY 0.702128 (-3625 2875);
PAINT GREEN (-3625 2875);
DISPLAY INVISIBLE (-3625 2875);
FORCEPROP 1 LAST PATH I188
J 2
(-3298 3000);
DISPLAY 0.872340 (-3298 3000);
PAINT GREEN (-3298 3000);
DISPLAY INVISIBLE (-3298 3000);
FORCEPROP 2 LAST ROOM RISER1
J 0
(-3800 3050);
DISPLAY 0.829787 (-3800 3050);
PAINT RED (-3800 3050);
DISPLAY INVISIBLE (-3800 3050);
FORCEADD TAP..6
R 2
(-3450 3050);
FORCEPROP 3 LASTPIN (-3500 3050) SIG_NAME P5E_CPU1_P3_TX_DN<1>
J 0
(-3490 3060);
DISPLAY 0.659574 (-3490 3060);
PAINT MONO (-3490 3060);
DISPLAY INVISIBLE (-3490 3060);
FORCEPROP 1 LASTPIN (-3500 3050) BN 1
J 2
(-3448 3058);
DISPLAY 0.489362 (-3448 3058);
PAINT MONO (-3448 3058);
FORCEPROP 2 LAST BOM_COST IO_SLOT
J 0
(-3950 3150);
DISPLAY 0.829787 (-3950 3150);
DISPLAY INVISIBLE (-3950 3150);
FORCEPROP 2 LAST CDS_LIB mstr_standard
J 0
(-3450 3050);
DISPLAY INVISIBLE (-3450 3050);
FORCEPROP 1 LAST BODY_TYPE PLUMBING
J 2
(-3450 3000);
DISPLAY 0.702128 (-3450 3000);
PAINT GREEN (-3450 3000);
DISPLAY INVISIBLE (-3450 3000);
FORCEPROP 1 LAST HDL_TAP TRUE
J 2
(-3775 2925);
DISPLAY 0.702128 (-3775 2925);
PAINT GREEN (-3775 2925);
DISPLAY INVISIBLE (-3775 2925);
FORCEPROP 1 LAST PATH I189
J 2
(-3448 3050);
DISPLAY 0.872340 (-3448 3050);
PAINT GREEN (-3448 3050);
DISPLAY INVISIBLE (-3448 3050);
FORCEPROP 2 LAST ROOM RISER1
J 0
(-3950 3100);
DISPLAY 0.829787 (-3950 3100);
PAINT RED (-3950 3100);
DISPLAY INVISIBLE (-3950 3100);
FORCEADD TAP..6
R 2
(-3450 2950);
FORCEPROP 3 LASTPIN (-3500 2950) SIG_NAME P5E_CPU1_P3_TX_DN<2>
J 0
(-3490 2960);
DISPLAY 0.659574 (-3490 2960);
PAINT MONO (-3490 2960);
DISPLAY INVISIBLE (-3490 2960);
FORCEPROP 1 LASTPIN (-3500 2950) BN 2
J 2
(-3448 2958);
DISPLAY 0.489362 (-3448 2958);
PAINT MONO (-3448 2958);
FORCEPROP 2 LAST BOM_COST IO_SLOT
J 0
(-3950 3050);
DISPLAY 0.829787 (-3950 3050);
DISPLAY INVISIBLE (-3950 3050);
FORCEPROP 2 LAST CDS_LIB standard
J 0
(-3450 2950);
DISPLAY INVISIBLE (-3450 2950);
FORCEPROP 1 LAST BODY_TYPE PLUMBING
J 2
(-3450 2900);
DISPLAY 0.702128 (-3450 2900);
PAINT GREEN (-3450 2900);
DISPLAY INVISIBLE (-3450 2900);
FORCEPROP 1 LAST HDL_TAP TRUE
J 2
(-3775 2825);
DISPLAY 0.702128 (-3775 2825);
PAINT GREEN (-3775 2825);
DISPLAY INVISIBLE (-3775 2825);
FORCEPROP 1 LAST PATH I190
J 2
(-3448 2950);
DISPLAY 0.872340 (-3448 2950);
PAINT GREEN (-3448 2950);
DISPLAY INVISIBLE (-3448 2950);
FORCEPROP 2 LAST ROOM RISER1
J 0
(-3950 3000);
DISPLAY 0.829787 (-3950 3000);
PAINT RED (-3950 3000);
DISPLAY INVISIBLE (-3950 3000);
FORCEADD TAP..6
R 2
(-3450 2850);
FORCEPROP 3 LASTPIN (-3500 2850) SIG_NAME P5E_CPU1_P3_TX_DN<3>
J 0
(-3490 2860);
DISPLAY 0.659574 (-3490 2860);
PAINT MONO (-3490 2860);
DISPLAY INVISIBLE (-3490 2860);
FORCEPROP 1 LASTPIN (-3500 2850) BN 3
J 2
(-3448 2858);
DISPLAY 0.489362 (-3448 2858);
PAINT MONO (-3448 2858);
FORCEPROP 2 LAST BOM_COST IO_SLOT
J 0
(-3950 2950);
DISPLAY 0.829787 (-3950 2950);
DISPLAY INVISIBLE (-3950 2950);
FORCEPROP 2 LAST CDS_LIB standard
J 0
(-3450 2850);
DISPLAY INVISIBLE (-3450 2850);
FORCEPROP 1 LAST BODY_TYPE PLUMBING
J 2
(-3450 2800);
DISPLAY 0.702128 (-3450 2800);
PAINT GREEN (-3450 2800);
DISPLAY INVISIBLE (-3450 2800);
FORCEPROP 1 LAST HDL_TAP TRUE
J 2
(-3775 2725);
DISPLAY 0.702128 (-3775 2725);
PAINT GREEN (-3775 2725);
DISPLAY INVISIBLE (-3775 2725);
FORCEPROP 1 LAST PATH I191
J 2
(-3448 2850);
DISPLAY 0.872340 (-3448 2850);
PAINT GREEN (-3448 2850);
DISPLAY INVISIBLE (-3448 2850);
FORCEPROP 2 LAST ROOM RISER1
J 0
(-3950 2900);
DISPLAY 0.829787 (-3950 2900);
PAINT RED (-3950 2900);
DISPLAY INVISIBLE (-3950 2900);
FORCEADD TAP..6
R 2
(-3300 2800);
FORCEPROP 3 LASTPIN (-3350 2800) SIG_NAME P5E_CPU1_P3_TX_DP<3>
J 0
(-3340 2810);
DISPLAY 0.659574 (-3340 2810);
PAINT MONO (-3340 2810);
DISPLAY INVISIBLE (-3340 2810);
FORCEPROP 1 LASTPIN (-3350 2800) BN 3
J 2
(-3298 2808);
DISPLAY 0.489362 (-3298 2808);
PAINT MONO (-3298 2808);
FORCEPROP 2 LAST BOM_COST IO_SLOT
J 0
(-3800 2900);
DISPLAY 0.829787 (-3800 2900);
DISPLAY INVISIBLE (-3800 2900);
FORCEPROP 2 LAST CDS_LIB standard
J 0
(-3300 2800);
DISPLAY INVISIBLE (-3300 2800);
FORCEPROP 1 LAST BODY_TYPE PLUMBING
J 2
(-3300 2750);
DISPLAY 0.702128 (-3300 2750);
PAINT GREEN (-3300 2750);
DISPLAY INVISIBLE (-3300 2750);
FORCEPROP 1 LAST HDL_TAP TRUE
J 2
(-3625 2675);
DISPLAY 0.702128 (-3625 2675);
PAINT GREEN (-3625 2675);
DISPLAY INVISIBLE (-3625 2675);
FORCEPROP 1 LAST PATH I192
J 2
(-3298 2800);
DISPLAY 0.872340 (-3298 2800);
PAINT GREEN (-3298 2800);
DISPLAY INVISIBLE (-3298 2800);
FORCEPROP 2 LAST ROOM RISER1
J 0
(-3800 2850);
DISPLAY 0.829787 (-3800 2850);
PAINT RED (-3800 2850);
DISPLAY INVISIBLE (-3800 2850);
FORCEADD TAP..6
R 2
(-3300 2700);
FORCEPROP 3 LASTPIN (-3350 2700) SIG_NAME P5E_CPU1_P3_TX_DP<4>
J 0
(-3340 2710);
DISPLAY 0.659574 (-3340 2710);
PAINT MONO (-3340 2710);
DISPLAY INVISIBLE (-3340 2710);
FORCEPROP 1 LASTPIN (-3350 2700) BN 4
J 2
(-3298 2708);
DISPLAY 0.489362 (-3298 2708);
PAINT MONO (-3298 2708);
FORCEPROP 2 LAST BOM_COST IO_SLOT
J 0
(-3800 2800);
DISPLAY 0.829787 (-3800 2800);
DISPLAY INVISIBLE (-3800 2800);
FORCEPROP 2 LAST CDS_LIB standard
J 0
(-3300 2700);
DISPLAY INVISIBLE (-3300 2700);
FORCEPROP 1 LAST BODY_TYPE PLUMBING
J 2
(-3300 2650);
DISPLAY 0.702128 (-3300 2650);
PAINT GREEN (-3300 2650);
DISPLAY INVISIBLE (-3300 2650);
FORCEPROP 1 LAST HDL_TAP TRUE
J 2
(-3625 2575);
DISPLAY 0.702128 (-3625 2575);
PAINT GREEN (-3625 2575);
DISPLAY INVISIBLE (-3625 2575);
FORCEPROP 1 LAST PATH I193
J 2
(-3298 2700);
DISPLAY 0.872340 (-3298 2700);
PAINT GREEN (-3298 2700);
DISPLAY INVISIBLE (-3298 2700);
FORCEPROP 2 LAST ROOM RISER1
J 0
(-3800 2750);
DISPLAY 0.829787 (-3800 2750);
PAINT RED (-3800 2750);
DISPLAY INVISIBLE (-3800 2750);
FORCEADD TAP..6
R 2
(-3300 2600);
FORCEPROP 3 LASTPIN (-3350 2600) SIG_NAME P5E_CPU1_P3_TX_DP<5>
J 0
(-3340 2610);
DISPLAY 0.659574 (-3340 2610);
PAINT MONO (-3340 2610);
DISPLAY INVISIBLE (-3340 2610);
FORCEPROP 1 LASTPIN (-3350 2600) BN 5
J 2
(-3298 2608);
DISPLAY 0.489362 (-3298 2608);
PAINT MONO (-3298 2608);
FORCEPROP 2 LAST BOM_COST IO_SLOT
J 0
(-3800 2700);
DISPLAY 0.829787 (-3800 2700);
DISPLAY INVISIBLE (-3800 2700);
FORCEPROP 2 LAST CDS_LIB standard
J 0
(-3300 2600);
DISPLAY INVISIBLE (-3300 2600);
FORCEPROP 1 LAST BODY_TYPE PLUMBING
J 2
(-3300 2550);
DISPLAY 0.702128 (-3300 2550);
PAINT GREEN (-3300 2550);
DISPLAY INVISIBLE (-3300 2550);
FORCEPROP 1 LAST HDL_TAP TRUE
J 2
(-3625 2475);
DISPLAY 0.702128 (-3625 2475);
PAINT GREEN (-3625 2475);
DISPLAY INVISIBLE (-3625 2475);
FORCEPROP 1 LAST PATH I194
J 2
(-3298 2600);
DISPLAY 0.872340 (-3298 2600);
PAINT GREEN (-3298 2600);
DISPLAY INVISIBLE (-3298 2600);
FORCEPROP 2 LAST ROOM RISER1
J 0
(-3800 2650);
DISPLAY 0.829787 (-3800 2650);
PAINT RED (-3800 2650);
DISPLAY INVISIBLE (-3800 2650);
FORCEADD TAP..6
R 2
(-3450 2750);
FORCEPROP 3 LASTPIN (-3500 2750) SIG_NAME P5E_CPU1_P3_TX_DN<4>
J 0
(-3490 2760);
DISPLAY 0.659574 (-3490 2760);
PAINT MONO (-3490 2760);
DISPLAY INVISIBLE (-3490 2760);
FORCEPROP 1 LASTPIN (-3500 2750) BN 4
J 2
(-3448 2758);
DISPLAY 0.489362 (-3448 2758);
PAINT MONO (-3448 2758);
FORCEPROP 2 LAST BOM_COST IO_SLOT
J 0
(-3950 2850);
DISPLAY 0.829787 (-3950 2850);
DISPLAY INVISIBLE (-3950 2850);
FORCEPROP 2 LAST CDS_LIB standard
J 0
(-3450 2750);
DISPLAY INVISIBLE (-3450 2750);
FORCEPROP 1 LAST BODY_TYPE PLUMBING
J 2
(-3450 2700);
DISPLAY 0.702128 (-3450 2700);
PAINT GREEN (-3450 2700);
DISPLAY INVISIBLE (-3450 2700);
FORCEPROP 1 LAST HDL_TAP TRUE
J 2
(-3775 2625);
DISPLAY 0.702128 (-3775 2625);
PAINT GREEN (-3775 2625);
DISPLAY INVISIBLE (-3775 2625);
FORCEPROP 1 LAST PATH I195
J 2
(-3448 2750);
DISPLAY 0.872340 (-3448 2750);
PAINT GREEN (-3448 2750);
DISPLAY INVISIBLE (-3448 2750);
FORCEPROP 2 LAST ROOM RISER1
J 0
(-3950 2800);
DISPLAY 0.829787 (-3950 2800);
PAINT RED (-3950 2800);
DISPLAY INVISIBLE (-3950 2800);
FORCEADD TAP..6
R 2
(-3450 2650);
FORCEPROP 3 LASTPIN (-3500 2650) SIG_NAME P5E_CPU1_P3_TX_DN<5>
J 0
(-3490 2660);
DISPLAY 0.659574 (-3490 2660);
PAINT MONO (-3490 2660);
DISPLAY INVISIBLE (-3490 2660);
FORCEPROP 1 LASTPIN (-3500 2650) BN 5
J 2
(-3448 2658);
DISPLAY 0.489362 (-3448 2658);
PAINT MONO (-3448 2658);
FORCEPROP 2 LAST BOM_COST IO_SLOT
J 0
(-3950 2750);
DISPLAY 0.829787 (-3950 2750);
DISPLAY INVISIBLE (-3950 2750);
FORCEPROP 2 LAST CDS_LIB standard
J 0
(-3450 2650);
DISPLAY INVISIBLE (-3450 2650);
FORCEPROP 1 LAST BODY_TYPE PLUMBING
J 2
(-3450 2600);
DISPLAY 0.702128 (-3450 2600);
PAINT GREEN (-3450 2600);
DISPLAY INVISIBLE (-3450 2600);
FORCEPROP 1 LAST HDL_TAP TRUE
J 2
(-3775 2525);
DISPLAY 0.702128 (-3775 2525);
PAINT GREEN (-3775 2525);
DISPLAY INVISIBLE (-3775 2525);
FORCEPROP 1 LAST PATH I196
J 2
(-3448 2650);
DISPLAY 0.872340 (-3448 2650);
PAINT GREEN (-3448 2650);
DISPLAY INVISIBLE (-3448 2650);
FORCEPROP 2 LAST ROOM RISER1
J 0
(-3950 2700);
DISPLAY 0.829787 (-3950 2700);
PAINT RED (-3950 2700);
DISPLAY INVISIBLE (-3950 2700);
FORCEADD TAP..6
R 2
(-3300 2400);
FORCEPROP 3 LASTPIN (-3350 2400) SIG_NAME P5E_CPU1_P3_TX_DP<7>
J 0
(-3340 2410);
DISPLAY 0.659574 (-3340 2410);
PAINT MONO (-3340 2410);
DISPLAY INVISIBLE (-3340 2410);
FORCEPROP 1 LASTPIN (-3350 2400) BN 7
J 2
(-3298 2408);
DISPLAY 0.489362 (-3298 2408);
PAINT MONO (-3298 2408);
FORCEPROP 2 LAST BOM_COST IO_SLOT
J 0
(-3800 2500);
DISPLAY 0.829787 (-3800 2500);
DISPLAY INVISIBLE (-3800 2500);
FORCEPROP 2 LAST CDS_LIB standard
J 0
(-3300 2400);
DISPLAY INVISIBLE (-3300 2400);
FORCEPROP 1 LAST BODY_TYPE PLUMBING
J 2
(-3300 2350);
DISPLAY 0.702128 (-3300 2350);
PAINT GREEN (-3300 2350);
DISPLAY INVISIBLE (-3300 2350);
FORCEPROP 1 LAST HDL_TAP TRUE
J 2
(-3625 2275);
DISPLAY 0.702128 (-3625 2275);
PAINT GREEN (-3625 2275);
DISPLAY INVISIBLE (-3625 2275);
FORCEPROP 1 LAST PATH I197
J 2
(-3298 2400);
DISPLAY 0.872340 (-3298 2400);
PAINT GREEN (-3298 2400);
DISPLAY INVISIBLE (-3298 2400);
FORCEPROP 2 LAST ROOM RISER1
J 0
(-3800 2450);
DISPLAY 0.829787 (-3800 2450);
PAINT RED (-3800 2450);
DISPLAY INVISIBLE (-3800 2450);
FORCEADD TAP..6
R 2
(-3300 2500);
FORCEPROP 3 LASTPIN (-3350 2500) SIG_NAME P5E_CPU1_P3_TX_DP<6>
J 0
(-3340 2510);
DISPLAY 0.659574 (-3340 2510);
PAINT MONO (-3340 2510);
DISPLAY INVISIBLE (-3340 2510);
FORCEPROP 1 LASTPIN (-3350 2500) BN 6
J 2
(-3298 2508);
DISPLAY 0.489362 (-3298 2508);
PAINT MONO (-3298 2508);
FORCEPROP 2 LAST BOM_COST IO_SLOT
J 0
(-3800 2600);
DISPLAY 0.829787 (-3800 2600);
DISPLAY INVISIBLE (-3800 2600);
FORCEPROP 2 LAST CDS_LIB standard
J 0
(-3300 2500);
DISPLAY INVISIBLE (-3300 2500);
FORCEPROP 1 LAST BODY_TYPE PLUMBING
J 2
(-3300 2450);
DISPLAY 0.702128 (-3300 2450);
PAINT GREEN (-3300 2450);
DISPLAY INVISIBLE (-3300 2450);
FORCEPROP 1 LAST HDL_TAP TRUE
J 2
(-3625 2375);
DISPLAY 0.702128 (-3625 2375);
PAINT GREEN (-3625 2375);
DISPLAY INVISIBLE (-3625 2375);
FORCEPROP 1 LAST PATH I198
J 2
(-3298 2500);
DISPLAY 0.872340 (-3298 2500);
PAINT GREEN (-3298 2500);
DISPLAY INVISIBLE (-3298 2500);
FORCEPROP 2 LAST ROOM RISER1
J 0
(-3800 2550);
DISPLAY 0.829787 (-3800 2550);
PAINT RED (-3800 2550);
DISPLAY INVISIBLE (-3800 2550);
FORCEADD TAP..6
R 2
(-3450 2550);
FORCEPROP 3 LASTPIN (-3500 2550) SIG_NAME P5E_CPU1_P3_TX_DN<6>
J 0
(-3490 2560);
DISPLAY 0.659574 (-3490 2560);
PAINT MONO (-3490 2560);
DISPLAY INVISIBLE (-3490 2560);
FORCEPROP 1 LASTPIN (-3500 2550) BN 6
J 2
(-3448 2558);
DISPLAY 0.489362 (-3448 2558);
PAINT MONO (-3448 2558);
FORCEPROP 2 LAST BOM_COST IO_SLOT
J 0
(-3950 2650);
DISPLAY 0.829787 (-3950 2650);
DISPLAY INVISIBLE (-3950 2650);
FORCEPROP 2 LAST CDS_LIB standard
J 0
(-3450 2550);
DISPLAY INVISIBLE (-3450 2550);
FORCEPROP 1 LAST BODY_TYPE PLUMBING
J 2
(-3450 2500);
DISPLAY 0.702128 (-3450 2500);
PAINT GREEN (-3450 2500);
DISPLAY INVISIBLE (-3450 2500);
FORCEPROP 1 LAST HDL_TAP TRUE
J 2
(-3775 2425);
DISPLAY 0.702128 (-3775 2425);
PAINT GREEN (-3775 2425);
DISPLAY INVISIBLE (-3775 2425);
FORCEPROP 1 LAST PATH I199
J 2
(-3448 2550);
DISPLAY 0.872340 (-3448 2550);
PAINT GREEN (-3448 2550);
DISPLAY INVISIBLE (-3448 2550);
FORCEPROP 2 LAST ROOM RISER1
J 0
(-3950 2600);
DISPLAY 0.829787 (-3950 2600);
PAINT RED (-3950 2600);
DISPLAY INVISIBLE (-3950 2600);
FORCEADD TAP..6
R 2
(-3450 2450);
FORCEPROP 3 LASTPIN (-3500 2450) SIG_NAME P5E_CPU1_P3_TX_DN<7>
J 0
(-3490 2460);
DISPLAY 0.659574 (-3490 2460);
PAINT MONO (-3490 2460);
DISPLAY INVISIBLE (-3490 2460);
FORCEPROP 1 LASTPIN (-3500 2450) BN 7
J 2
(-3448 2458);
DISPLAY 0.489362 (-3448 2458);
PAINT MONO (-3448 2458);
FORCEPROP 2 LAST BOM_COST IO_SLOT
J 0
(-3950 2550);
DISPLAY 0.829787 (-3950 2550);
DISPLAY INVISIBLE (-3950 2550);
FORCEPROP 2 LAST CDS_LIB standard
J 0
(-3450 2450);
DISPLAY INVISIBLE (-3450 2450);
FORCEPROP 1 LAST BODY_TYPE PLUMBING
J 2
(-3450 2400);
DISPLAY 0.702128 (-3450 2400);
PAINT GREEN (-3450 2400);
DISPLAY INVISIBLE (-3450 2400);
FORCEPROP 1 LAST HDL_TAP TRUE
J 2
(-3775 2325);
DISPLAY 0.702128 (-3775 2325);
PAINT GREEN (-3775 2325);
DISPLAY INVISIBLE (-3775 2325);
FORCEPROP 1 LAST PATH I200
J 2
(-3448 2450);
DISPLAY 0.872340 (-3448 2450);
PAINT GREEN (-3448 2450);
DISPLAY INVISIBLE (-3448 2450);
FORCEPROP 2 LAST ROOM RISER1
J 0
(-3950 2500);
DISPLAY 0.829787 (-3950 2500);
PAINT RED (-3950 2500);
DISPLAY INVISIBLE (-3950 2500);
FORCEADD TAP..6
R 2
(-3450 2350);
FORCEPROP 3 LASTPIN (-3500 2350) SIG_NAME P5E_CPU1_P3_TX_DN<8>
J 0
(-3490 2360);
DISPLAY 0.659574 (-3490 2360);
PAINT MONO (-3490 2360);
DISPLAY INVISIBLE (-3490 2360);
FORCEPROP 1 LASTPIN (-3500 2350) BN 8
J 2
(-3448 2358);
DISPLAY 0.489362 (-3448 2358);
PAINT MONO (-3448 2358);
FORCEPROP 2 LAST BOM_COST IO_SLOT
J 0
(-3950 2450);
DISPLAY 0.829787 (-3950 2450);
DISPLAY INVISIBLE (-3950 2450);
FORCEPROP 2 LAST CDS_LIB standard
J 0
(-3450 2350);
DISPLAY INVISIBLE (-3450 2350);
FORCEPROP 1 LAST BODY_TYPE PLUMBING
J 2
(-3450 2300);
DISPLAY 0.702128 (-3450 2300);
PAINT GREEN (-3450 2300);
DISPLAY INVISIBLE (-3450 2300);
FORCEPROP 1 LAST HDL_TAP TRUE
J 2
(-3775 2225);
DISPLAY 0.702128 (-3775 2225);
PAINT GREEN (-3775 2225);
DISPLAY INVISIBLE (-3775 2225);
FORCEPROP 1 LAST PATH I201
J 2
(-3448 2350);
DISPLAY 0.872340 (-3448 2350);
PAINT GREEN (-3448 2350);
DISPLAY INVISIBLE (-3448 2350);
FORCEPROP 2 LAST ROOM RISER1
J 0
(-3950 2400);
DISPLAY 0.829787 (-3950 2400);
PAINT RED (-3950 2400);
DISPLAY INVISIBLE (-3950 2400);
FORCEADD TAP..6
R 2
(-3300 2300);
FORCEPROP 3 LASTPIN (-3350 2300) SIG_NAME P5E_CPU1_P3_TX_DP<8>
J 0
(-3340 2310);
DISPLAY 0.659574 (-3340 2310);
PAINT MONO (-3340 2310);
DISPLAY INVISIBLE (-3340 2310);
FORCEPROP 1 LASTPIN (-3350 2300) BN 8
J 2
(-3298 2308);
DISPLAY 0.489362 (-3298 2308);
PAINT MONO (-3298 2308);
FORCEPROP 2 LAST BOM_COST IO_SLOT
J 0
(-3800 2400);
DISPLAY 0.829787 (-3800 2400);
DISPLAY INVISIBLE (-3800 2400);
FORCEPROP 2 LAST CDS_LIB standard
J 0
(-3300 2300);
DISPLAY INVISIBLE (-3300 2300);
FORCEPROP 1 LAST BODY_TYPE PLUMBING
J 2
(-3300 2250);
DISPLAY 0.702128 (-3300 2250);
PAINT GREEN (-3300 2250);
DISPLAY INVISIBLE (-3300 2250);
FORCEPROP 1 LAST HDL_TAP TRUE
J 2
(-3625 2175);
DISPLAY 0.702128 (-3625 2175);
PAINT GREEN (-3625 2175);
DISPLAY INVISIBLE (-3625 2175);
FORCEPROP 1 LAST PATH I202
J 2
(-3298 2300);
DISPLAY 0.872340 (-3298 2300);
PAINT GREEN (-3298 2300);
DISPLAY INVISIBLE (-3298 2300);
FORCEPROP 2 LAST ROOM RISER1
J 0
(-3800 2350);
DISPLAY 0.829787 (-3800 2350);
PAINT RED (-3800 2350);
DISPLAY INVISIBLE (-3800 2350);
FORCEADD TAP..6
R 2
(-3300 2200);
FORCEPROP 3 LASTPIN (-3350 2200) SIG_NAME P5E_CPU1_P3_TX_DP<9>
J 0
(-3340 2210);
DISPLAY 0.659574 (-3340 2210);
PAINT MONO (-3340 2210);
DISPLAY INVISIBLE (-3340 2210);
FORCEPROP 1 LASTPIN (-3350 2200) BN 9
J 2
(-3298 2208);
DISPLAY 0.489362 (-3298 2208);
PAINT MONO (-3298 2208);
FORCEPROP 2 LAST BOM_COST IO_SLOT
J 0
(-3800 2300);
DISPLAY 0.829787 (-3800 2300);
DISPLAY INVISIBLE (-3800 2300);
FORCEPROP 2 LAST CDS_LIB standard
J 0
(-3300 2200);
DISPLAY INVISIBLE (-3300 2200);
FORCEPROP 1 LAST BODY_TYPE PLUMBING
J 2
(-3300 2150);
DISPLAY 0.702128 (-3300 2150);
PAINT GREEN (-3300 2150);
DISPLAY INVISIBLE (-3300 2150);
FORCEPROP 1 LAST HDL_TAP TRUE
J 2
(-3625 2075);
DISPLAY 0.702128 (-3625 2075);
PAINT GREEN (-3625 2075);
DISPLAY INVISIBLE (-3625 2075);
FORCEPROP 1 LAST PATH I203
J 2
(-3298 2200);
DISPLAY 0.872340 (-3298 2200);
PAINT GREEN (-3298 2200);
DISPLAY INVISIBLE (-3298 2200);
FORCEPROP 2 LAST ROOM RISER1
J 0
(-3800 2250);
DISPLAY 0.829787 (-3800 2250);
PAINT RED (-3800 2250);
DISPLAY INVISIBLE (-3800 2250);
FORCEADD TAP..6
R 2
(-3300 2100);
FORCEPROP 3 LASTPIN (-3350 2100) SIG_NAME P5E_CPU1_P3_TX_DP<10>
J 0
(-3340 2110);
DISPLAY 0.659574 (-3340 2110);
PAINT MONO (-3340 2110);
DISPLAY INVISIBLE (-3340 2110);
FORCEPROP 1 LASTPIN (-3350 2100) BN 10
J 2
(-3298 2108);
DISPLAY 0.489362 (-3298 2108);
PAINT MONO (-3298 2108);
FORCEPROP 2 LAST BOM_COST IO_SLOT
J 0
(-3800 2200);
DISPLAY 0.829787 (-3800 2200);
DISPLAY INVISIBLE (-3800 2200);
FORCEPROP 2 LAST CDS_LIB standard
J 0
(-3300 2100);
DISPLAY INVISIBLE (-3300 2100);
FORCEPROP 1 LAST BODY_TYPE PLUMBING
J 2
(-3300 2050);
DISPLAY 0.702128 (-3300 2050);
PAINT GREEN (-3300 2050);
DISPLAY INVISIBLE (-3300 2050);
FORCEPROP 1 LAST HDL_TAP TRUE
J 2
(-3625 1975);
DISPLAY 0.702128 (-3625 1975);
PAINT GREEN (-3625 1975);
DISPLAY INVISIBLE (-3625 1975);
FORCEPROP 1 LAST PATH I204
J 2
(-3298 2100);
DISPLAY 0.872340 (-3298 2100);
PAINT GREEN (-3298 2100);
DISPLAY INVISIBLE (-3298 2100);
FORCEPROP 2 LAST ROOM RISER1
J 0
(-3800 2150);
DISPLAY 0.829787 (-3800 2150);
PAINT RED (-3800 2150);
DISPLAY INVISIBLE (-3800 2150);
FORCEADD TAP..6
R 2
(-3450 2250);
FORCEPROP 3 LASTPIN (-3500 2250) SIG_NAME P5E_CPU1_P3_TX_DN<9>
J 0
(-3490 2260);
DISPLAY 0.659574 (-3490 2260);
PAINT MONO (-3490 2260);
DISPLAY INVISIBLE (-3490 2260);
FORCEPROP 1 LASTPIN (-3500 2250) BN 9
J 2
(-3448 2258);
DISPLAY 0.489362 (-3448 2258);
PAINT MONO (-3448 2258);
FORCEPROP 2 LAST BOM_COST IO_SLOT
J 0
(-3950 2350);
DISPLAY 0.829787 (-3950 2350);
DISPLAY INVISIBLE (-3950 2350);
FORCEPROP 2 LAST CDS_LIB standard
J 0
(-3450 2250);
DISPLAY INVISIBLE (-3450 2250);
FORCEPROP 1 LAST BODY_TYPE PLUMBING
J 2
(-3450 2200);
DISPLAY 0.702128 (-3450 2200);
PAINT GREEN (-3450 2200);
DISPLAY INVISIBLE (-3450 2200);
FORCEPROP 1 LAST HDL_TAP TRUE
J 2
(-3775 2125);
DISPLAY 0.702128 (-3775 2125);
PAINT GREEN (-3775 2125);
DISPLAY INVISIBLE (-3775 2125);
FORCEPROP 1 LAST PATH I205
J 2
(-3448 2250);
DISPLAY 0.872340 (-3448 2250);
PAINT GREEN (-3448 2250);
DISPLAY INVISIBLE (-3448 2250);
FORCEPROP 2 LAST ROOM RISER1
J 0
(-3950 2300);
DISPLAY 0.829787 (-3950 2300);
PAINT RED (-3950 2300);
DISPLAY INVISIBLE (-3950 2300);
FORCEADD TAP..6
R 2
(-3450 2150);
FORCEPROP 3 LASTPIN (-3500 2150) SIG_NAME P5E_CPU1_P3_TX_DN<10>
J 0
(-3490 2160);
DISPLAY 0.659574 (-3490 2160);
PAINT MONO (-3490 2160);
DISPLAY INVISIBLE (-3490 2160);
FORCEPROP 1 LASTPIN (-3500 2150) BN 10
J 2
(-3448 2158);
DISPLAY 0.489362 (-3448 2158);
PAINT MONO (-3448 2158);
FORCEPROP 2 LAST BOM_COST IO_SLOT
J 0
(-3950 2250);
DISPLAY 0.829787 (-3950 2250);
DISPLAY INVISIBLE (-3950 2250);
FORCEPROP 2 LAST CDS_LIB standard
J 0
(-3450 2150);
DISPLAY INVISIBLE (-3450 2150);
FORCEPROP 1 LAST BODY_TYPE PLUMBING
J 2
(-3450 2100);
DISPLAY 0.702128 (-3450 2100);
PAINT GREEN (-3450 2100);
DISPLAY INVISIBLE (-3450 2100);
FORCEPROP 1 LAST HDL_TAP TRUE
J 2
(-3775 2025);
DISPLAY 0.702128 (-3775 2025);
PAINT GREEN (-3775 2025);
DISPLAY INVISIBLE (-3775 2025);
FORCEPROP 1 LAST PATH I206
J 2
(-3448 2150);
DISPLAY 0.872340 (-3448 2150);
PAINT GREEN (-3448 2150);
DISPLAY INVISIBLE (-3448 2150);
FORCEPROP 2 LAST ROOM RISER1
J 0
(-3950 2200);
DISPLAY 0.829787 (-3950 2200);
PAINT RED (-3950 2200);
DISPLAY INVISIBLE (-3950 2200);
FORCEADD TAP..6
R 2
(-3450 2050);
FORCEPROP 3 LASTPIN (-3500 2050) SIG_NAME P5E_CPU1_P3_TX_DN<11>
J 0
(-3490 2060);
DISPLAY 0.659574 (-3490 2060);
PAINT MONO (-3490 2060);
DISPLAY INVISIBLE (-3490 2060);
FORCEPROP 1 LASTPIN (-3500 2050) BN 11
J 2
(-3448 2058);
DISPLAY 0.489362 (-3448 2058);
PAINT MONO (-3448 2058);
FORCEPROP 2 LAST BOM_COST IO_SLOT
J 0
(-3950 2150);
DISPLAY 0.829787 (-3950 2150);
DISPLAY INVISIBLE (-3950 2150);
FORCEPROP 2 LAST CDS_LIB standard
J 0
(-3450 2050);
DISPLAY INVISIBLE (-3450 2050);
FORCEPROP 1 LAST BODY_TYPE PLUMBING
J 2
(-3450 2000);
DISPLAY 0.702128 (-3450 2000);
PAINT GREEN (-3450 2000);
DISPLAY INVISIBLE (-3450 2000);
FORCEPROP 1 LAST HDL_TAP TRUE
J 2
(-3775 1925);
DISPLAY 0.702128 (-3775 1925);
PAINT GREEN (-3775 1925);
DISPLAY INVISIBLE (-3775 1925);
FORCEPROP 1 LAST PATH I207
J 2
(-3448 2050);
DISPLAY 0.872340 (-3448 2050);
PAINT GREEN (-3448 2050);
DISPLAY INVISIBLE (-3448 2050);
FORCEPROP 2 LAST ROOM RISER1
J 0
(-3950 2100);
DISPLAY 0.829787 (-3950 2100);
PAINT RED (-3950 2100);
DISPLAY INVISIBLE (-3950 2100);
FORCEADD TAP..6
R 2
(-3300 1800);
FORCEPROP 3 LASTPIN (-3350 1800) SIG_NAME P5E_CPU1_P3_TX_DP<13>
J 0
(-3340 1810);
DISPLAY 0.659574 (-3340 1810);
PAINT MONO (-3340 1810);
DISPLAY INVISIBLE (-3340 1810);
FORCEPROP 1 LASTPIN (-3350 1800) BN 13
J 2
(-3298 1808);
DISPLAY 0.489362 (-3298 1808);
PAINT MONO (-3298 1808);
FORCEPROP 2 LAST BOM_COST IO_SLOT
J 0
(-3800 1900);
DISPLAY 0.829787 (-3800 1900);
DISPLAY INVISIBLE (-3800 1900);
FORCEPROP 2 LAST CDS_LIB standard
J 0
(-3300 1800);
DISPLAY INVISIBLE (-3300 1800);
FORCEPROP 1 LAST BODY_TYPE PLUMBING
J 2
(-3300 1750);
DISPLAY 0.702128 (-3300 1750);
PAINT GREEN (-3300 1750);
DISPLAY INVISIBLE (-3300 1750);
FORCEPROP 1 LAST HDL_TAP TRUE
J 2
(-3625 1675);
DISPLAY 0.702128 (-3625 1675);
PAINT GREEN (-3625 1675);
DISPLAY INVISIBLE (-3625 1675);
FORCEPROP 1 LAST PATH I208
J 2
(-3298 1800);
DISPLAY 0.872340 (-3298 1800);
PAINT GREEN (-3298 1800);
DISPLAY INVISIBLE (-3298 1800);
FORCEPROP 2 LAST ROOM RISER1
J 0
(-3800 1850);
DISPLAY 0.829787 (-3800 1850);
PAINT RED (-3800 1850);
DISPLAY INVISIBLE (-3800 1850);
FORCEADD TAP..6
R 2
(-3300 1900);
FORCEPROP 3 LASTPIN (-3350 1900) SIG_NAME P5E_CPU1_P3_TX_DP<12>
J 0
(-3340 1910);
DISPLAY 0.659574 (-3340 1910);
PAINT MONO (-3340 1910);
DISPLAY INVISIBLE (-3340 1910);
FORCEPROP 1 LASTPIN (-3350 1900) BN 12
J 2
(-3298 1908);
DISPLAY 0.489362 (-3298 1908);
PAINT MONO (-3298 1908);
FORCEPROP 2 LAST BOM_COST IO_SLOT
J 0
(-3800 2000);
DISPLAY 0.829787 (-3800 2000);
DISPLAY INVISIBLE (-3800 2000);
FORCEPROP 2 LAST CDS_LIB standard
J 0
(-3300 1900);
DISPLAY INVISIBLE (-3300 1900);
FORCEPROP 1 LAST BODY_TYPE PLUMBING
J 2
(-3300 1850);
DISPLAY 0.702128 (-3300 1850);
PAINT GREEN (-3300 1850);
DISPLAY INVISIBLE (-3300 1850);
FORCEPROP 1 LAST HDL_TAP TRUE
J 2
(-3625 1775);
DISPLAY 0.702128 (-3625 1775);
PAINT GREEN (-3625 1775);
DISPLAY INVISIBLE (-3625 1775);
FORCEPROP 1 LAST PATH I209
J 2
(-3298 1900);
DISPLAY 0.872340 (-3298 1900);
PAINT GREEN (-3298 1900);
DISPLAY INVISIBLE (-3298 1900);
FORCEPROP 2 LAST ROOM RISER1
J 0
(-3800 1950);
DISPLAY 0.829787 (-3800 1950);
PAINT RED (-3800 1950);
DISPLAY INVISIBLE (-3800 1950);
FORCEADD TAP..6
R 2
(-3300 2000);
FORCEPROP 3 LASTPIN (-3350 2000) SIG_NAME P5E_CPU1_P3_TX_DP<11>
J 0
(-3340 2010);
DISPLAY 0.659574 (-3340 2010);
PAINT MONO (-3340 2010);
DISPLAY INVISIBLE (-3340 2010);
FORCEPROP 1 LASTPIN (-3350 2000) BN 11
J 2
(-3298 2008);
DISPLAY 0.489362 (-3298 2008);
PAINT MONO (-3298 2008);
FORCEPROP 2 LAST BOM_COST IO_SLOT
J 0
(-3800 2100);
DISPLAY 0.829787 (-3800 2100);
DISPLAY INVISIBLE (-3800 2100);
FORCEPROP 2 LAST CDS_LIB standard
J 0
(-3300 2000);
DISPLAY INVISIBLE (-3300 2000);
FORCEPROP 1 LAST BODY_TYPE PLUMBING
J 2
(-3300 1950);
DISPLAY 0.702128 (-3300 1950);
PAINT GREEN (-3300 1950);
DISPLAY INVISIBLE (-3300 1950);
FORCEPROP 1 LAST HDL_TAP TRUE
J 2
(-3625 1875);
DISPLAY 0.702128 (-3625 1875);
PAINT GREEN (-3625 1875);
DISPLAY INVISIBLE (-3625 1875);
FORCEPROP 1 LAST PATH I210
J 2
(-3298 2000);
DISPLAY 0.872340 (-3298 2000);
PAINT GREEN (-3298 2000);
DISPLAY INVISIBLE (-3298 2000);
FORCEPROP 2 LAST ROOM RISER1
J 0
(-3800 2050);
DISPLAY 0.829787 (-3800 2050);
PAINT RED (-3800 2050);
DISPLAY INVISIBLE (-3800 2050);
FORCEADD TAP..6
R 2
(-3450 1950);
FORCEPROP 3 LASTPIN (-3500 1950) SIG_NAME P5E_CPU1_P3_TX_DN<12>
J 0
(-3490 1960);
DISPLAY 0.659574 (-3490 1960);
PAINT MONO (-3490 1960);
DISPLAY INVISIBLE (-3490 1960);
FORCEPROP 1 LASTPIN (-3500 1950) BN 12
J 2
(-3448 1958);
DISPLAY 0.489362 (-3448 1958);
PAINT MONO (-3448 1958);
FORCEPROP 2 LAST BOM_COST IO_SLOT
J 0
(-3950 2050);
DISPLAY 0.829787 (-3950 2050);
DISPLAY INVISIBLE (-3950 2050);
FORCEPROP 2 LAST CDS_LIB standard
J 0
(-3450 1950);
DISPLAY INVISIBLE (-3450 1950);
FORCEPROP 1 LAST BODY_TYPE PLUMBING
J 2
(-3450 1900);
DISPLAY 0.702128 (-3450 1900);
PAINT GREEN (-3450 1900);
DISPLAY INVISIBLE (-3450 1900);
FORCEPROP 1 LAST HDL_TAP TRUE
J 2
(-3775 1825);
DISPLAY 0.702128 (-3775 1825);
PAINT GREEN (-3775 1825);
DISPLAY INVISIBLE (-3775 1825);
FORCEPROP 1 LAST PATH I211
J 2
(-3448 1950);
DISPLAY 0.872340 (-3448 1950);
PAINT GREEN (-3448 1950);
DISPLAY INVISIBLE (-3448 1950);
FORCEPROP 2 LAST ROOM RISER1
J 0
(-3950 2000);
DISPLAY 0.829787 (-3950 2000);
PAINT RED (-3950 2000);
DISPLAY INVISIBLE (-3950 2000);
FORCEADD TAP..6
R 2
(-3450 1850);
FORCEPROP 3 LASTPIN (-3500 1850) SIG_NAME P5E_CPU1_P3_TX_DN<13>
J 0
(-3490 1860);
DISPLAY 0.659574 (-3490 1860);
PAINT MONO (-3490 1860);
DISPLAY INVISIBLE (-3490 1860);
FORCEPROP 1 LASTPIN (-3500 1850) BN 13
J 2
(-3448 1858);
DISPLAY 0.489362 (-3448 1858);
PAINT MONO (-3448 1858);
FORCEPROP 2 LAST BOM_COST IO_SLOT
J 0
(-3950 1950);
DISPLAY 0.829787 (-3950 1950);
DISPLAY INVISIBLE (-3950 1950);
FORCEPROP 2 LAST CDS_LIB standard
J 0
(-3450 1850);
DISPLAY INVISIBLE (-3450 1850);
FORCEPROP 1 LAST BODY_TYPE PLUMBING
J 2
(-3450 1800);
DISPLAY 0.702128 (-3450 1800);
PAINT GREEN (-3450 1800);
DISPLAY INVISIBLE (-3450 1800);
FORCEPROP 1 LAST HDL_TAP TRUE
J 2
(-3775 1725);
DISPLAY 0.702128 (-3775 1725);
PAINT GREEN (-3775 1725);
DISPLAY INVISIBLE (-3775 1725);
FORCEPROP 1 LAST PATH I212
J 2
(-3448 1850);
DISPLAY 0.872340 (-3448 1850);
PAINT GREEN (-3448 1850);
DISPLAY INVISIBLE (-3448 1850);
FORCEPROP 2 LAST ROOM RISER1
J 0
(-3950 1900);
DISPLAY 0.829787 (-3950 1900);
PAINT RED (-3950 1900);
DISPLAY INVISIBLE (-3950 1900);
FORCEADD TAP..6
R 2
(-3300 1600);
FORCEPROP 3 LASTPIN (-3350 1600) SIG_NAME P5E_CPU1_P3_TX_DP<15>
J 0
(-3340 1610);
DISPLAY 0.659574 (-3340 1610);
PAINT MONO (-3340 1610);
DISPLAY INVISIBLE (-3340 1610);
FORCEPROP 1 LASTPIN (-3350 1600) BN 15
J 2
(-3298 1608);
DISPLAY 0.489362 (-3298 1608);
PAINT MONO (-3298 1608);
FORCEPROP 2 LAST BOM_COST IO_SLOT
J 0
(-3800 1700);
DISPLAY 0.829787 (-3800 1700);
DISPLAY INVISIBLE (-3800 1700);
FORCEPROP 2 LAST CDS_LIB standard
J 0
(-3300 1600);
DISPLAY INVISIBLE (-3300 1600);
FORCEPROP 1 LAST BODY_TYPE PLUMBING
J 2
(-3300 1550);
DISPLAY 0.702128 (-3300 1550);
PAINT GREEN (-3300 1550);
DISPLAY INVISIBLE (-3300 1550);
FORCEPROP 1 LAST HDL_TAP TRUE
J 2
(-3625 1475);
DISPLAY 0.702128 (-3625 1475);
PAINT GREEN (-3625 1475);
DISPLAY INVISIBLE (-3625 1475);
FORCEPROP 1 LAST PATH I213
J 2
(-3298 1600);
DISPLAY 0.872340 (-3298 1600);
PAINT GREEN (-3298 1600);
DISPLAY INVISIBLE (-3298 1600);
FORCEPROP 2 LAST ROOM RISER1
J 0
(-3800 1650);
DISPLAY 0.829787 (-3800 1650);
PAINT RED (-3800 1650);
DISPLAY INVISIBLE (-3800 1650);
FORCEADD TAP..6
R 2
(-3300 1700);
FORCEPROP 3 LASTPIN (-3350 1700) SIG_NAME P5E_CPU1_P3_TX_DP<14>
J 0
(-3340 1710);
DISPLAY 0.659574 (-3340 1710);
PAINT MONO (-3340 1710);
DISPLAY INVISIBLE (-3340 1710);
FORCEPROP 1 LASTPIN (-3350 1700) BN 14
J 2
(-3298 1708);
DISPLAY 0.489362 (-3298 1708);
PAINT MONO (-3298 1708);
FORCEPROP 2 LAST CDS_LIB standard
J 0
(-3300 1700);
DISPLAY INVISIBLE (-3300 1700);
FORCEPROP 2 LAST BOM_COST IO_SLOT
J 0
(-3800 1800);
DISPLAY 0.829787 (-3800 1800);
DISPLAY INVISIBLE (-3800 1800);
FORCEPROP 1 LAST BODY_TYPE PLUMBING
J 2
(-3300 1650);
DISPLAY 0.702128 (-3300 1650);
PAINT GREEN (-3300 1650);
DISPLAY INVISIBLE (-3300 1650);
FORCEPROP 1 LAST HDL_TAP TRUE
J 2
(-3625 1575);
DISPLAY 0.702128 (-3625 1575);
PAINT GREEN (-3625 1575);
DISPLAY INVISIBLE (-3625 1575);
FORCEPROP 1 LAST PATH I214
J 2
(-3298 1700);
DISPLAY 0.872340 (-3298 1700);
PAINT GREEN (-3298 1700);
DISPLAY INVISIBLE (-3298 1700);
FORCEPROP 2 LAST ROOM RISER1
J 0
(-3800 1750);
DISPLAY 0.829787 (-3800 1750);
PAINT RED (-3800 1750);
DISPLAY INVISIBLE (-3800 1750);
FORCEADD TAP..6
R 2
(-3450 1750);
FORCEPROP 3 LASTPIN (-3500 1750) SIG_NAME P5E_CPU1_P3_TX_DN<14>
J 0
(-3490 1760);
DISPLAY 0.659574 (-3490 1760);
PAINT MONO (-3490 1760);
DISPLAY INVISIBLE (-3490 1760);
FORCEPROP 1 LASTPIN (-3500 1750) BN 14
J 2
(-3448 1758);
DISPLAY 0.489362 (-3448 1758);
PAINT MONO (-3448 1758);
FORCEPROP 2 LAST BOM_COST IO_SLOT
J 0
(-3950 1850);
DISPLAY 0.829787 (-3950 1850);
DISPLAY INVISIBLE (-3950 1850);
FORCEPROP 2 LAST CDS_LIB standard
J 0
(-3450 1750);
DISPLAY INVISIBLE (-3450 1750);
FORCEPROP 1 LAST BODY_TYPE PLUMBING
J 2
(-3450 1700);
DISPLAY 0.702128 (-3450 1700);
PAINT GREEN (-3450 1700);
DISPLAY INVISIBLE (-3450 1700);
FORCEPROP 1 LAST HDL_TAP TRUE
J 2
(-3775 1625);
DISPLAY 0.702128 (-3775 1625);
PAINT GREEN (-3775 1625);
DISPLAY INVISIBLE (-3775 1625);
FORCEPROP 1 LAST PATH I215
J 2
(-3448 1750);
DISPLAY 0.872340 (-3448 1750);
PAINT GREEN (-3448 1750);
DISPLAY INVISIBLE (-3448 1750);
FORCEPROP 2 LAST ROOM RISER1
J 0
(-3950 1800);
DISPLAY 0.829787 (-3950 1800);
PAINT RED (-3950 1800);
DISPLAY INVISIBLE (-3950 1800);
FORCEADD TAP..6
R 2
(-3450 1650);
FORCEPROP 3 LASTPIN (-3500 1650) SIG_NAME P5E_CPU1_P3_TX_DN<15>
J 0
(-3490 1660);
DISPLAY 0.659574 (-3490 1660);
PAINT MONO (-3490 1660);
DISPLAY INVISIBLE (-3490 1660);
FORCEPROP 1 LASTPIN (-3500 1650) BN 15
J 2
(-3448 1658);
DISPLAY 0.489362 (-3448 1658);
PAINT MONO (-3448 1658);
FORCEPROP 2 LAST BOM_COST IO_SLOT
J 0
(-3950 1750);
DISPLAY 0.829787 (-3950 1750);
DISPLAY INVISIBLE (-3950 1750);
FORCEPROP 2 LAST CDS_LIB standard
J 0
(-3450 1650);
DISPLAY INVISIBLE (-3450 1650);
FORCEPROP 1 LAST BODY_TYPE PLUMBING
J 2
(-3450 1600);
DISPLAY 0.702128 (-3450 1600);
PAINT GREEN (-3450 1600);
DISPLAY INVISIBLE (-3450 1600);
FORCEPROP 1 LAST HDL_TAP TRUE
J 2
(-3775 1525);
DISPLAY 0.702128 (-3775 1525);
PAINT GREEN (-3775 1525);
DISPLAY INVISIBLE (-3775 1525);
FORCEPROP 1 LAST PATH I216
J 2
(-3448 1650);
DISPLAY 0.872340 (-3448 1650);
PAINT GREEN (-3448 1650);
DISPLAY INVISIBLE (-3448 1650);
FORCEPROP 2 LAST ROOM RISER1
J 0
(-3950 1700);
DISPLAY 0.829787 (-3950 1700);
PAINT RED (-3950 1700);
DISPLAY INVISIBLE (-3950 1700);
FORCEADD TAP..6
(-5875 3150);
FORCEPROP 3 LASTPIN (-5825 3150) SIG_NAME P5E_CPU1_P3_RX_DP<0>
J 0
(-5815 3160);
DISPLAY 0.659574 (-5815 3160);
PAINT MONO (-5815 3160);
DISPLAY INVISIBLE (-5815 3160);
FORCEPROP 1 LASTPIN (-5825 3150) BN 0
J 0
(-5877 3158);
DISPLAY 0.489362 (-5877 3158);
PAINT MONO (-5877 3158);
FORCEPROP 2 LAST CDS_LIB mstr_standard
J 0
(-5875 3150);
DISPLAY INVISIBLE (-5875 3150);
FORCEPROP 1 LAST BODY_TYPE PLUMBING
J 0
(-5875 3100);
DISPLAY 0.574468 (-5875 3100);
PAINT GREEN (-5875 3100);
DISPLAY INVISIBLE (-5875 3100);
FORCEPROP 1 LAST HDL_TAP TRUE
J 0
(-5550 3025);
DISPLAY 0.574468 (-5550 3025);
PAINT GREEN (-5550 3025);
DISPLAY INVISIBLE (-5550 3025);
FORCEPROP 1 LAST PATH I251
J 0
(-5877 3150);
DISPLAY 0.872340 (-5877 3150);
PAINT GREEN (-5877 3150);
DISPLAY INVISIBLE (-5877 3150);
FORCEADD TAP..6
(-5875 2950);
FORCEPROP 3 LASTPIN (-5825 2950) SIG_NAME P5E_CPU1_P3_RX_DP<2>
J 0
(-5815 2960);
DISPLAY 0.659574 (-5815 2960);
PAINT MONO (-5815 2960);
DISPLAY INVISIBLE (-5815 2960);
FORCEPROP 1 LASTPIN (-5825 2950) BN 2
J 0
(-5877 2958);
DISPLAY 0.489362 (-5877 2958);
PAINT MONO (-5877 2958);
FORCEPROP 2 LAST CDS_LIB mstr_standard
J 0
(-5875 2950);
DISPLAY INVISIBLE (-5875 2950);
FORCEPROP 1 LAST BODY_TYPE PLUMBING
J 0
(-5875 2900);
DISPLAY 0.574468 (-5875 2900);
PAINT GREEN (-5875 2900);
DISPLAY INVISIBLE (-5875 2900);
FORCEPROP 1 LAST HDL_TAP TRUE
J 0
(-5550 2825);
DISPLAY 0.574468 (-5550 2825);
PAINT GREEN (-5550 2825);
DISPLAY INVISIBLE (-5550 2825);
FORCEPROP 1 LAST PATH I253
J 0
(-5877 2950);
DISPLAY 0.872340 (-5877 2950);
PAINT GREEN (-5877 2950);
DISPLAY INVISIBLE (-5877 2950);
FORCEADD TAP..6
(-5875 3050);
FORCEPROP 3 LASTPIN (-5825 3050) SIG_NAME P5E_CPU1_P3_RX_DP<1>
J 0
(-5815 3060);
DISPLAY 0.659574 (-5815 3060);
PAINT MONO (-5815 3060);
DISPLAY INVISIBLE (-5815 3060);
FORCEPROP 1 LASTPIN (-5825 3050) BN 1
J 0
(-5877 3058);
DISPLAY 0.489362 (-5877 3058);
PAINT MONO (-5877 3058);
FORCEPROP 2 LAST CDS_LIB mstr_standard
J 0
(-5875 3050);
DISPLAY INVISIBLE (-5875 3050);
FORCEPROP 1 LAST BODY_TYPE PLUMBING
J 0
(-5875 3000);
DISPLAY 0.574468 (-5875 3000);
PAINT GREEN (-5875 3000);
DISPLAY INVISIBLE (-5875 3000);
FORCEPROP 1 LAST HDL_TAP TRUE
J 0
(-5550 2925);
DISPLAY 0.574468 (-5550 2925);
PAINT GREEN (-5550 2925);
DISPLAY INVISIBLE (-5550 2925);
FORCEPROP 1 LAST PATH I254
J 0
(-5877 3050);
DISPLAY 0.872340 (-5877 3050);
PAINT GREEN (-5877 3050);
DISPLAY INVISIBLE (-5877 3050);
FORCEADD TAP..6
(-5875 2850);
FORCEPROP 3 LASTPIN (-5825 2850) SIG_NAME P5E_CPU1_P3_RX_DP<3>
J 0
(-5815 2860);
DISPLAY 0.659574 (-5815 2860);
PAINT MONO (-5815 2860);
DISPLAY INVISIBLE (-5815 2860);
FORCEPROP 1 LASTPIN (-5825 2850) BN 3
J 0
(-5877 2858);
DISPLAY 0.489362 (-5877 2858);
PAINT MONO (-5877 2858);
FORCEPROP 2 LAST CDS_LIB standard
J 0
(-5875 2850);
DISPLAY INVISIBLE (-5875 2850);
FORCEPROP 1 LAST BODY_TYPE PLUMBING
J 0
(-5875 2800);
DISPLAY 0.574468 (-5875 2800);
PAINT GREEN (-5875 2800);
DISPLAY INVISIBLE (-5875 2800);
FORCEPROP 1 LAST HDL_TAP TRUE
J 0
(-5550 2725);
DISPLAY 0.574468 (-5550 2725);
PAINT GREEN (-5550 2725);
DISPLAY INVISIBLE (-5550 2725);
FORCEPROP 1 LAST PATH I255
J 0
(-5877 2850);
DISPLAY 0.872340 (-5877 2850);
PAINT GREEN (-5877 2850);
DISPLAY INVISIBLE (-5877 2850);
FORCEADD TAP..6
(-5875 2750);
FORCEPROP 3 LASTPIN (-5825 2750) SIG_NAME P5E_CPU1_P3_RX_DP<4>
J 0
(-5815 2760);
DISPLAY 0.659574 (-5815 2760);
PAINT MONO (-5815 2760);
DISPLAY INVISIBLE (-5815 2760);
FORCEPROP 1 LASTPIN (-5825 2750) BN 4
J 0
(-5877 2758);
DISPLAY 0.489362 (-5877 2758);
PAINT MONO (-5877 2758);
FORCEPROP 2 LAST CDS_LIB standard
J 0
(-5875 2750);
DISPLAY INVISIBLE (-5875 2750);
FORCEPROP 1 LAST BODY_TYPE PLUMBING
J 0
(-5875 2700);
DISPLAY 0.574468 (-5875 2700);
PAINT GREEN (-5875 2700);
DISPLAY INVISIBLE (-5875 2700);
FORCEPROP 1 LAST HDL_TAP TRUE
J 0
(-5550 2625);
DISPLAY 0.574468 (-5550 2625);
PAINT GREEN (-5550 2625);
DISPLAY INVISIBLE (-5550 2625);
FORCEPROP 1 LAST PATH I256
J 0
(-5877 2750);
DISPLAY 0.872340 (-5877 2750);
PAINT GREEN (-5877 2750);
DISPLAY INVISIBLE (-5877 2750);
FORCEADD TAP..6
(-5875 2650);
FORCEPROP 3 LASTPIN (-5825 2650) SIG_NAME P5E_CPU1_P3_RX_DP<5>
J 0
(-5815 2660);
DISPLAY 0.659574 (-5815 2660);
PAINT MONO (-5815 2660);
DISPLAY INVISIBLE (-5815 2660);
FORCEPROP 1 LASTPIN (-5825 2650) BN 5
J 0
(-5877 2658);
DISPLAY 0.489362 (-5877 2658);
PAINT MONO (-5877 2658);
FORCEPROP 2 LAST CDS_LIB standard
J 0
(-5875 2650);
DISPLAY INVISIBLE (-5875 2650);
FORCEPROP 1 LAST BODY_TYPE PLUMBING
J 0
(-5875 2600);
DISPLAY 0.574468 (-5875 2600);
PAINT GREEN (-5875 2600);
DISPLAY INVISIBLE (-5875 2600);
FORCEPROP 1 LAST HDL_TAP TRUE
J 0
(-5550 2525);
DISPLAY 0.574468 (-5550 2525);
PAINT GREEN (-5550 2525);
DISPLAY INVISIBLE (-5550 2525);
FORCEPROP 1 LAST PATH I257
J 0
(-5877 2650);
DISPLAY 0.872340 (-5877 2650);
PAINT GREEN (-5877 2650);
DISPLAY INVISIBLE (-5877 2650);
FORCEADD TAP..6
(-5875 2550);
FORCEPROP 3 LASTPIN (-5825 2550) SIG_NAME P5E_CPU1_P3_RX_DP<6>
J 0
(-5815 2560);
DISPLAY 0.659574 (-5815 2560);
PAINT MONO (-5815 2560);
DISPLAY INVISIBLE (-5815 2560);
FORCEPROP 1 LASTPIN (-5825 2550) BN 6
J 0
(-5877 2558);
DISPLAY 0.489362 (-5877 2558);
PAINT MONO (-5877 2558);
FORCEPROP 2 LAST CDS_LIB standard
J 0
(-5875 2550);
DISPLAY INVISIBLE (-5875 2550);
FORCEPROP 1 LAST BODY_TYPE PLUMBING
J 0
(-5875 2500);
DISPLAY 0.574468 (-5875 2500);
PAINT GREEN (-5875 2500);
DISPLAY INVISIBLE (-5875 2500);
FORCEPROP 1 LAST HDL_TAP TRUE
J 0
(-5550 2425);
DISPLAY 0.574468 (-5550 2425);
PAINT GREEN (-5550 2425);
DISPLAY INVISIBLE (-5550 2425);
FORCEPROP 1 LAST PATH I263
J 0
(-5877 2550);
DISPLAY 0.872340 (-5877 2550);
PAINT GREEN (-5877 2550);
DISPLAY INVISIBLE (-5877 2550);
FORCEADD TAP..6
(-5875 2450);
FORCEPROP 3 LASTPIN (-5825 2450) SIG_NAME P5E_CPU1_P3_RX_DP<7>
J 0
(-5815 2460);
DISPLAY 0.659574 (-5815 2460);
PAINT MONO (-5815 2460);
DISPLAY INVISIBLE (-5815 2460);
FORCEPROP 1 LASTPIN (-5825 2450) BN 7
J 0
(-5877 2458);
DISPLAY 0.489362 (-5877 2458);
PAINT MONO (-5877 2458);
FORCEPROP 2 LAST CDS_LIB mstr_standard
J 0
(-5875 2450);
DISPLAY INVISIBLE (-5875 2450);
FORCEPROP 1 LAST BODY_TYPE PLUMBING
J 0
(-5875 2400);
DISPLAY 0.574468 (-5875 2400);
PAINT GREEN (-5875 2400);
DISPLAY INVISIBLE (-5875 2400);
FORCEPROP 1 LAST HDL_TAP TRUE
J 0
(-5550 2325);
DISPLAY 0.574468 (-5550 2325);
PAINT GREEN (-5550 2325);
DISPLAY INVISIBLE (-5550 2325);
FORCEPROP 1 LAST PATH I285
J 0
(-5877 2450);
DISPLAY 0.872340 (-5877 2450);
PAINT GREEN (-5877 2450);
DISPLAY INVISIBLE (-5877 2450);
FORCEADD TAP..6
(-5875 2050);
FORCEPROP 3 LASTPIN (-5825 2050) SIG_NAME P5E_CPU1_P3_RX_DP<11>
J 0
(-5815 2060);
DISPLAY 0.659574 (-5815 2060);
PAINT MONO (-5815 2060);
DISPLAY INVISIBLE (-5815 2060);
FORCEPROP 1 LASTPIN (-5825 2050) BN 11
J 0
(-5877 2058);
DISPLAY 0.489362 (-5877 2058);
PAINT MONO (-5877 2058);
FORCEPROP 2 LAST CDS_LIB standard
J 0
(-5875 2050);
DISPLAY INVISIBLE (-5875 2050);
FORCEPROP 1 LAST BODY_TYPE PLUMBING
J 0
(-5875 2000);
DISPLAY 0.574468 (-5875 2000);
PAINT GREEN (-5875 2000);
DISPLAY INVISIBLE (-5875 2000);
FORCEPROP 1 LAST HDL_TAP TRUE
J 0
(-5550 1925);
DISPLAY 0.574468 (-5550 1925);
PAINT GREEN (-5550 1925);
DISPLAY INVISIBLE (-5550 1925);
FORCEPROP 1 LAST PATH I286
J 0
(-5877 2050);
DISPLAY 0.872340 (-5877 2050);
PAINT GREEN (-5877 2050);
DISPLAY INVISIBLE (-5877 2050);
FORCEADD TAP..6
(-5875 1950);
FORCEPROP 3 LASTPIN (-5825 1950) SIG_NAME P5E_CPU1_P3_RX_DP<12>
J 0
(-5815 1960);
DISPLAY 0.659574 (-5815 1960);
PAINT MONO (-5815 1960);
DISPLAY INVISIBLE (-5815 1960);
FORCEPROP 1 LASTPIN (-5825 1950) BN 12
J 0
(-5877 1958);
DISPLAY 0.489362 (-5877 1958);
PAINT MONO (-5877 1958);
FORCEPROP 2 LAST CDS_LIB standard
J 0
(-5875 1950);
DISPLAY INVISIBLE (-5875 1950);
FORCEPROP 1 LAST BODY_TYPE PLUMBING
J 0
(-5875 1900);
DISPLAY 0.574468 (-5875 1900);
PAINT GREEN (-5875 1900);
DISPLAY INVISIBLE (-5875 1900);
FORCEPROP 1 LAST HDL_TAP TRUE
J 0
(-5550 1825);
DISPLAY 0.574468 (-5550 1825);
PAINT GREEN (-5550 1825);
DISPLAY INVISIBLE (-5550 1825);
FORCEPROP 1 LAST PATH I287
J 0
(-5877 1950);
DISPLAY 0.872340 (-5877 1950);
PAINT GREEN (-5877 1950);
DISPLAY INVISIBLE (-5877 1950);
FORCEADD TAP..6
(-5875 1850);
FORCEPROP 3 LASTPIN (-5825 1850) SIG_NAME P5E_CPU1_P3_RX_DP<13>
J 0
(-5815 1860);
DISPLAY 0.659574 (-5815 1860);
PAINT MONO (-5815 1860);
DISPLAY INVISIBLE (-5815 1860);
FORCEPROP 1 LASTPIN (-5825 1850) BN 13
J 0
(-5877 1858);
DISPLAY 0.489362 (-5877 1858);
PAINT MONO (-5877 1858);
FORCEPROP 2 LAST CDS_LIB standard
J 0
(-5875 1850);
DISPLAY INVISIBLE (-5875 1850);
FORCEPROP 1 LAST BODY_TYPE PLUMBING
J 0
(-5875 1800);
DISPLAY 0.574468 (-5875 1800);
PAINT GREEN (-5875 1800);
DISPLAY INVISIBLE (-5875 1800);
FORCEPROP 1 LAST HDL_TAP TRUE
J 0
(-5550 1725);
DISPLAY 0.574468 (-5550 1725);
PAINT GREEN (-5550 1725);
DISPLAY INVISIBLE (-5550 1725);
FORCEPROP 1 LAST PATH I288
J 0
(-5877 1850);
DISPLAY 0.872340 (-5877 1850);
PAINT GREEN (-5877 1850);
DISPLAY INVISIBLE (-5877 1850);
FORCEADD TAP..6
(-5875 2350);
FORCEPROP 3 LASTPIN (-5825 2350) SIG_NAME P5E_CPU1_P3_RX_DP<8>
J 0
(-5815 2360);
DISPLAY 0.659574 (-5815 2360);
PAINT MONO (-5815 2360);
DISPLAY INVISIBLE (-5815 2360);
FORCEPROP 1 LASTPIN (-5825 2350) BN 8
J 0
(-5877 2358);
DISPLAY 0.489362 (-5877 2358);
PAINT MONO (-5877 2358);
FORCEPROP 2 LAST CDS_LIB mstr_standard
J 0
(-5875 2350);
DISPLAY INVISIBLE (-5875 2350);
FORCEPROP 1 LAST BODY_TYPE PLUMBING
J 0
(-5875 2300);
DISPLAY 0.574468 (-5875 2300);
PAINT GREEN (-5875 2300);
DISPLAY INVISIBLE (-5875 2300);
FORCEPROP 1 LAST HDL_TAP TRUE
J 0
(-5550 2225);
DISPLAY 0.574468 (-5550 2225);
PAINT GREEN (-5550 2225);
DISPLAY INVISIBLE (-5550 2225);
FORCEPROP 1 LAST PATH I292
J 0
(-5877 2350);
DISPLAY 0.872340 (-5877 2350);
PAINT GREEN (-5877 2350);
DISPLAY INVISIBLE (-5877 2350);
FORCEADD TAP..6
(-5875 2250);
FORCEPROP 3 LASTPIN (-5825 2250) SIG_NAME P5E_CPU1_P3_RX_DP<9>
J 0
(-5815 2260);
DISPLAY 0.659574 (-5815 2260);
PAINT MONO (-5815 2260);
DISPLAY INVISIBLE (-5815 2260);
FORCEPROP 1 LASTPIN (-5825 2250) BN 9
J 0
(-5877 2258);
DISPLAY 0.489362 (-5877 2258);
PAINT MONO (-5877 2258);
FORCEPROP 2 LAST CDS_LIB mstr_standard
J 0
(-5875 2250);
DISPLAY INVISIBLE (-5875 2250);
FORCEPROP 1 LAST BODY_TYPE PLUMBING
J 0
(-5875 2200);
DISPLAY 0.574468 (-5875 2200);
PAINT GREEN (-5875 2200);
DISPLAY INVISIBLE (-5875 2200);
FORCEPROP 1 LAST HDL_TAP TRUE
J 0
(-5550 2125);
DISPLAY 0.574468 (-5550 2125);
PAINT GREEN (-5550 2125);
DISPLAY INVISIBLE (-5550 2125);
FORCEPROP 1 LAST PATH I293
J 0
(-5877 2250);
DISPLAY 0.872340 (-5877 2250);
PAINT GREEN (-5877 2250);
DISPLAY INVISIBLE (-5877 2250);
FORCEADD TAP..6
(-5875 2150);
FORCEPROP 3 LASTPIN (-5825 2150) SIG_NAME P5E_CPU1_P3_RX_DP<10>
J 0
(-5815 2160);
DISPLAY 0.659574 (-5815 2160);
PAINT MONO (-5815 2160);
DISPLAY INVISIBLE (-5815 2160);
FORCEPROP 1 LASTPIN (-5825 2150) BN 10
J 0
(-5877 2158);
DISPLAY 0.489362 (-5877 2158);
PAINT MONO (-5877 2158);
FORCEPROP 2 LAST CDS_LIB standard
J 0
(-5875 2150);
DISPLAY INVISIBLE (-5875 2150);
FORCEPROP 1 LAST BODY_TYPE PLUMBING
J 0
(-5875 2100);
DISPLAY 0.574468 (-5875 2100);
PAINT GREEN (-5875 2100);
DISPLAY INVISIBLE (-5875 2100);
FORCEPROP 1 LAST HDL_TAP TRUE
J 0
(-5550 2025);
DISPLAY 0.574468 (-5550 2025);
PAINT GREEN (-5550 2025);
DISPLAY INVISIBLE (-5550 2025);
FORCEPROP 1 LAST PATH I294
J 0
(-5877 2150);
DISPLAY 0.872340 (-5877 2150);
PAINT GREEN (-5877 2150);
DISPLAY INVISIBLE (-5877 2150);
FORCEADD TAP..6
(-5875 1750);
FORCEPROP 3 LASTPIN (-5825 1750) SIG_NAME P5E_CPU1_P3_RX_DP<14>
J 0
(-5815 1760);
DISPLAY 0.659574 (-5815 1760);
PAINT MONO (-5815 1760);
DISPLAY INVISIBLE (-5815 1760);
FORCEPROP 1 LASTPIN (-5825 1750) BN 14
J 0
(-5877 1758);
DISPLAY 0.489362 (-5877 1758);
PAINT MONO (-5877 1758);
FORCEPROP 2 LAST CDS_LIB standard
J 0
(-5875 1750);
DISPLAY INVISIBLE (-5875 1750);
FORCEPROP 1 LAST BODY_TYPE PLUMBING
J 0
(-5875 1700);
DISPLAY 0.574468 (-5875 1700);
PAINT GREEN (-5875 1700);
DISPLAY INVISIBLE (-5875 1700);
FORCEPROP 1 LAST HDL_TAP TRUE
J 0
(-5550 1625);
DISPLAY 0.574468 (-5550 1625);
PAINT GREEN (-5550 1625);
DISPLAY INVISIBLE (-5550 1625);
FORCEPROP 1 LAST PATH I299
J 0
(-5877 1750);
DISPLAY 0.872340 (-5877 1750);
PAINT GREEN (-5877 1750);
DISPLAY INVISIBLE (-5877 1750);
FORCEADD TAP..6
(-5875 1650);
FORCEPROP 3 LASTPIN (-5825 1650) SIG_NAME P5E_CPU1_P3_RX_DP<15>
J 0
(-5815 1660);
DISPLAY 0.659574 (-5815 1660);
PAINT MONO (-5815 1660);
DISPLAY INVISIBLE (-5815 1660);
FORCEPROP 1 LASTPIN (-5825 1650) BN 15
J 0
(-5877 1658);
DISPLAY 0.489362 (-5877 1658);
PAINT MONO (-5877 1658);
FORCEPROP 2 LAST CDS_LIB standard
J 0
(-5875 1650);
DISPLAY INVISIBLE (-5875 1650);
FORCEPROP 1 LAST BODY_TYPE PLUMBING
J 0
(-5875 1600);
DISPLAY 0.574468 (-5875 1600);
PAINT GREEN (-5875 1600);
DISPLAY INVISIBLE (-5875 1600);
FORCEPROP 1 LAST HDL_TAP TRUE
J 0
(-5550 1525);
DISPLAY 0.574468 (-5550 1525);
PAINT GREEN (-5550 1525);
DISPLAY INVISIBLE (-5550 1525);
FORCEPROP 1 LAST PATH I302
J 0
(-5877 1650);
DISPLAY 0.872340 (-5877 1650);
PAINT GREEN (-5877 1650);
DISPLAY INVISIBLE (-5877 1650);
FORCEADD TAP..6
(-6025 3000);
FORCEPROP 3 LASTPIN (-5975 3000) SIG_NAME P5E_CPU1_P3_RX_DN<1>
J 0
(-5965 3010);
DISPLAY 0.659574 (-5965 3010);
PAINT MONO (-5965 3010);
DISPLAY INVISIBLE (-5965 3010);
FORCEPROP 1 LASTPIN (-5975 3000) BN 1
J 0
(-6027 3008);
DISPLAY 0.489362 (-6027 3008);
PAINT MONO (-6027 3008);
FORCEPROP 2 LAST CDS_LIB mstr_standard
J 0
(-6025 3000);
DISPLAY INVISIBLE (-6025 3000);
FORCEPROP 1 LAST BODY_TYPE PLUMBING
J 0
(-6025 2950);
DISPLAY 0.574468 (-6025 2950);
PAINT GREEN (-6025 2950);
DISPLAY INVISIBLE (-6025 2950);
FORCEPROP 1 LAST HDL_TAP TRUE
J 0
(-5700 2875);
DISPLAY 0.574468 (-5700 2875);
PAINT GREEN (-5700 2875);
DISPLAY INVISIBLE (-5700 2875);
FORCEPROP 1 LAST PATH I303
J 0
(-6027 3000);
DISPLAY 0.872340 (-6027 3000);
PAINT GREEN (-6027 3000);
DISPLAY INVISIBLE (-6027 3000);
FORCEADD TAP..6
(-6025 3100);
FORCEPROP 3 LASTPIN (-5975 3100) SIG_NAME P5E_CPU1_P3_RX_DN<0>
J 0
(-5965 3110);
DISPLAY 0.659574 (-5965 3110);
PAINT MONO (-5965 3110);
DISPLAY INVISIBLE (-5965 3110);
FORCEPROP 1 LASTPIN (-5975 3100) BN 0
J 0
(-6027 3108);
DISPLAY 0.489362 (-6027 3108);
PAINT MONO (-6027 3108);
FORCEPROP 2 LAST CDS_LIB mstr_standard
J 0
(-6025 3100);
DISPLAY INVISIBLE (-6025 3100);
FORCEPROP 1 LAST BODY_TYPE PLUMBING
J 0
(-6025 3050);
DISPLAY 0.574468 (-6025 3050);
PAINT GREEN (-6025 3050);
DISPLAY INVISIBLE (-6025 3050);
FORCEPROP 1 LAST HDL_TAP TRUE
J 0
(-5700 2975);
DISPLAY 0.574468 (-5700 2975);
PAINT GREEN (-5700 2975);
DISPLAY INVISIBLE (-5700 2975);
FORCEPROP 1 LAST PATH I304
J 0
(-6027 3100);
DISPLAY 0.872340 (-6027 3100);
PAINT GREEN (-6027 3100);
DISPLAY INVISIBLE (-6027 3100);
FORCEADD TAP..6
(-6025 2900);
FORCEPROP 3 LASTPIN (-5975 2900) SIG_NAME P5E_CPU1_P3_RX_DN<2>
J 0
(-5965 2910);
DISPLAY 0.659574 (-5965 2910);
PAINT MONO (-5965 2910);
DISPLAY INVISIBLE (-5965 2910);
FORCEPROP 1 LASTPIN (-5975 2900) BN 2
J 0
(-6027 2908);
DISPLAY 0.489362 (-6027 2908);
PAINT MONO (-6027 2908);
FORCEPROP 2 LAST CDS_LIB standard
J 0
(-6025 2900);
DISPLAY INVISIBLE (-6025 2900);
FORCEPROP 1 LAST BODY_TYPE PLUMBING
J 0
(-6025 2850);
DISPLAY 0.574468 (-6025 2850);
PAINT GREEN (-6025 2850);
DISPLAY INVISIBLE (-6025 2850);
FORCEPROP 1 LAST HDL_TAP TRUE
J 0
(-5700 2775);
DISPLAY 0.574468 (-5700 2775);
PAINT GREEN (-5700 2775);
DISPLAY INVISIBLE (-5700 2775);
FORCEPROP 1 LAST PATH I305
J 0
(-6027 2900);
DISPLAY 0.872340 (-6027 2900);
PAINT GREEN (-6027 2900);
DISPLAY INVISIBLE (-6027 2900);
FORCEADD TAP..6
(-6025 2800);
FORCEPROP 3 LASTPIN (-5975 2800) SIG_NAME P5E_CPU1_P3_RX_DN<3>
J 0
(-5965 2810);
DISPLAY 0.659574 (-5965 2810);
PAINT MONO (-5965 2810);
DISPLAY INVISIBLE (-5965 2810);
FORCEPROP 1 LASTPIN (-5975 2800) BN 3
J 0
(-6027 2808);
DISPLAY 0.489362 (-6027 2808);
PAINT MONO (-6027 2808);
FORCEPROP 2 LAST CDS_LIB standard
J 0
(-6025 2800);
DISPLAY INVISIBLE (-6025 2800);
FORCEPROP 1 LAST BODY_TYPE PLUMBING
J 0
(-6025 2750);
DISPLAY 0.574468 (-6025 2750);
PAINT GREEN (-6025 2750);
DISPLAY INVISIBLE (-6025 2750);
FORCEPROP 1 LAST HDL_TAP TRUE
J 0
(-5700 2675);
DISPLAY 0.574468 (-5700 2675);
PAINT GREEN (-5700 2675);
DISPLAY INVISIBLE (-5700 2675);
FORCEPROP 1 LAST PATH I306
J 0
(-6027 2800);
DISPLAY 0.872340 (-6027 2800);
PAINT GREEN (-6027 2800);
DISPLAY INVISIBLE (-6027 2800);
FORCEADD TAP..6
(-6025 2700);
FORCEPROP 3 LASTPIN (-5975 2700) SIG_NAME P5E_CPU1_P3_RX_DN<4>
J 0
(-5965 2710);
DISPLAY 0.659574 (-5965 2710);
PAINT MONO (-5965 2710);
DISPLAY INVISIBLE (-5965 2710);
FORCEPROP 1 LASTPIN (-5975 2700) BN 4
J 0
(-6027 2708);
DISPLAY 0.489362 (-6027 2708);
PAINT MONO (-6027 2708);
FORCEPROP 2 LAST CDS_LIB standard
J 0
(-6025 2700);
DISPLAY INVISIBLE (-6025 2700);
FORCEPROP 1 LAST BODY_TYPE PLUMBING
J 0
(-6025 2650);
DISPLAY 0.574468 (-6025 2650);
PAINT GREEN (-6025 2650);
DISPLAY INVISIBLE (-6025 2650);
FORCEPROP 1 LAST HDL_TAP TRUE
J 0
(-5700 2575);
DISPLAY 0.574468 (-5700 2575);
PAINT GREEN (-5700 2575);
DISPLAY INVISIBLE (-5700 2575);
FORCEPROP 1 LAST PATH I307
J 0
(-6027 2700);
DISPLAY 0.872340 (-6027 2700);
PAINT GREEN (-6027 2700);
DISPLAY INVISIBLE (-6027 2700);
FORCEADD TAP..6
(-6025 2600);
FORCEPROP 3 LASTPIN (-5975 2600) SIG_NAME P5E_CPU1_P3_RX_DN<5>
J 0
(-5965 2610);
DISPLAY 0.659574 (-5965 2610);
PAINT MONO (-5965 2610);
DISPLAY INVISIBLE (-5965 2610);
FORCEPROP 1 LASTPIN (-5975 2600) BN 5
J 0
(-6027 2608);
DISPLAY 0.489362 (-6027 2608);
PAINT MONO (-6027 2608);
FORCEPROP 2 LAST CDS_LIB standard
J 0
(-6025 2600);
DISPLAY INVISIBLE (-6025 2600);
FORCEPROP 1 LAST BODY_TYPE PLUMBING
J 0
(-6025 2550);
DISPLAY 0.574468 (-6025 2550);
PAINT GREEN (-6025 2550);
DISPLAY INVISIBLE (-6025 2550);
FORCEPROP 1 LAST HDL_TAP TRUE
J 0
(-5700 2475);
DISPLAY 0.574468 (-5700 2475);
PAINT GREEN (-5700 2475);
DISPLAY INVISIBLE (-5700 2475);
FORCEPROP 1 LAST PATH I308
J 0
(-6027 2600);
DISPLAY 0.872340 (-6027 2600);
PAINT GREEN (-6027 2600);
DISPLAY INVISIBLE (-6027 2600);
FORCEADD TAP..6
(-6025 2500);
FORCEPROP 3 LASTPIN (-5975 2500) SIG_NAME P5E_CPU1_P3_RX_DN<6>
J 0
(-5965 2510);
DISPLAY 0.659574 (-5965 2510);
PAINT MONO (-5965 2510);
DISPLAY INVISIBLE (-5965 2510);
FORCEPROP 1 LASTPIN (-5975 2500) BN 6
J 0
(-6027 2508);
DISPLAY 0.489362 (-6027 2508);
PAINT MONO (-6027 2508);
FORCEPROP 2 LAST CDS_LIB standard
J 0
(-6025 2500);
DISPLAY INVISIBLE (-6025 2500);
FORCEPROP 1 LAST BODY_TYPE PLUMBING
J 0
(-6025 2450);
DISPLAY 0.574468 (-6025 2450);
PAINT GREEN (-6025 2450);
DISPLAY INVISIBLE (-6025 2450);
FORCEPROP 1 LAST HDL_TAP TRUE
J 0
(-5700 2375);
DISPLAY 0.574468 (-5700 2375);
PAINT GREEN (-5700 2375);
DISPLAY INVISIBLE (-5700 2375);
FORCEPROP 1 LAST PATH I309
J 0
(-6027 2500);
DISPLAY 0.872340 (-6027 2500);
PAINT GREEN (-6027 2500);
DISPLAY INVISIBLE (-6027 2500);
FORCEADD TAP..6
(-6025 2400);
FORCEPROP 3 LASTPIN (-5975 2400) SIG_NAME P5E_CPU1_P3_RX_DN<7>
J 0
(-5965 2410);
DISPLAY 0.659574 (-5965 2410);
PAINT MONO (-5965 2410);
DISPLAY INVISIBLE (-5965 2410);
FORCEPROP 1 LASTPIN (-5975 2400) BN 7
J 0
(-6027 2408);
DISPLAY 0.489362 (-6027 2408);
PAINT MONO (-6027 2408);
FORCEPROP 2 LAST CDS_LIB mstr_standard
J 0
(-6025 2400);
DISPLAY INVISIBLE (-6025 2400);
FORCEPROP 1 LAST BODY_TYPE PLUMBING
J 0
(-6025 2350);
DISPLAY 0.574468 (-6025 2350);
PAINT GREEN (-6025 2350);
DISPLAY INVISIBLE (-6025 2350);
FORCEPROP 1 LAST HDL_TAP TRUE
J 0
(-5700 2275);
DISPLAY 0.574468 (-5700 2275);
PAINT GREEN (-5700 2275);
DISPLAY INVISIBLE (-5700 2275);
FORCEPROP 1 LAST PATH I310
J 0
(-6027 2400);
DISPLAY 0.872340 (-6027 2400);
PAINT GREEN (-6027 2400);
DISPLAY INVISIBLE (-6027 2400);
FORCEADD TAP..6
(-6025 2200);
FORCEPROP 3 LASTPIN (-5975 2200) SIG_NAME P5E_CPU1_P3_RX_DN<9>
J 0
(-5965 2210);
DISPLAY 0.659574 (-5965 2210);
PAINT MONO (-5965 2210);
DISPLAY INVISIBLE (-5965 2210);
FORCEPROP 1 LASTPIN (-5975 2200) BN 9
J 0
(-6027 2208);
DISPLAY 0.489362 (-6027 2208);
PAINT MONO (-6027 2208);
FORCEPROP 2 LAST CDS_LIB standard
J 0
(-6025 2200);
DISPLAY INVISIBLE (-6025 2200);
FORCEPROP 1 LAST BODY_TYPE PLUMBING
J 0
(-6025 2150);
DISPLAY 0.574468 (-6025 2150);
PAINT GREEN (-6025 2150);
DISPLAY INVISIBLE (-6025 2150);
FORCEPROP 1 LAST HDL_TAP TRUE
J 0
(-5700 2075);
DISPLAY 0.574468 (-5700 2075);
PAINT GREEN (-5700 2075);
DISPLAY INVISIBLE (-5700 2075);
FORCEPROP 1 LAST PATH I311
J 0
(-6027 2200);
DISPLAY 0.872340 (-6027 2200);
PAINT GREEN (-6027 2200);
DISPLAY INVISIBLE (-6027 2200);
FORCEADD TAP..6
(-6025 2300);
FORCEPROP 3 LASTPIN (-5975 2300) SIG_NAME P5E_CPU1_P3_RX_DN<8>
J 0
(-5965 2310);
DISPLAY 0.659574 (-5965 2310);
PAINT MONO (-5965 2310);
DISPLAY INVISIBLE (-5965 2310);
FORCEPROP 1 LASTPIN (-5975 2300) BN 8
J 0
(-6027 2308);
DISPLAY 0.489362 (-6027 2308);
PAINT MONO (-6027 2308);
FORCEPROP 2 LAST CDS_LIB mstr_standard
J 0
(-6025 2300);
DISPLAY INVISIBLE (-6025 2300);
FORCEPROP 1 LAST BODY_TYPE PLUMBING
J 0
(-6025 2250);
DISPLAY 0.574468 (-6025 2250);
PAINT GREEN (-6025 2250);
DISPLAY INVISIBLE (-6025 2250);
FORCEPROP 1 LAST HDL_TAP TRUE
J 0
(-5700 2175);
DISPLAY 0.574468 (-5700 2175);
PAINT GREEN (-5700 2175);
DISPLAY INVISIBLE (-5700 2175);
FORCEPROP 1 LAST PATH I312
J 0
(-6027 2300);
DISPLAY 0.872340 (-6027 2300);
PAINT GREEN (-6027 2300);
DISPLAY INVISIBLE (-6027 2300);
FORCEADD TAP..6
(-6025 2100);
FORCEPROP 3 LASTPIN (-5975 2100) SIG_NAME P5E_CPU1_P3_RX_DN<10>
J 0
(-5965 2110);
DISPLAY 0.659574 (-5965 2110);
PAINT MONO (-5965 2110);
DISPLAY INVISIBLE (-5965 2110);
FORCEPROP 1 LASTPIN (-5975 2100) BN 10
J 0
(-6027 2108);
DISPLAY 0.489362 (-6027 2108);
PAINT MONO (-6027 2108);
FORCEPROP 2 LAST CDS_LIB standard
J 0
(-6025 2100);
DISPLAY INVISIBLE (-6025 2100);
FORCEPROP 1 LAST BODY_TYPE PLUMBING
J 0
(-6025 2050);
DISPLAY 0.574468 (-6025 2050);
PAINT GREEN (-6025 2050);
DISPLAY INVISIBLE (-6025 2050);
FORCEPROP 1 LAST HDL_TAP TRUE
J 0
(-5700 1975);
DISPLAY 0.574468 (-5700 1975);
PAINT GREEN (-5700 1975);
DISPLAY INVISIBLE (-5700 1975);
FORCEPROP 1 LAST PATH I313
J 0
(-6027 2100);
DISPLAY 0.872340 (-6027 2100);
PAINT GREEN (-6027 2100);
DISPLAY INVISIBLE (-6027 2100);
FORCEADD TAP..6
(-6025 2000);
FORCEPROP 3 LASTPIN (-5975 2000) SIG_NAME P5E_CPU1_P3_RX_DN<11>
J 0
(-5965 2010);
DISPLAY 0.659574 (-5965 2010);
PAINT MONO (-5965 2010);
DISPLAY INVISIBLE (-5965 2010);
FORCEPROP 1 LASTPIN (-5975 2000) BN 11
J 0
(-6027 2008);
DISPLAY 0.489362 (-6027 2008);
PAINT MONO (-6027 2008);
FORCEPROP 2 LAST CDS_LIB standard
J 0
(-6025 2000);
DISPLAY INVISIBLE (-6025 2000);
FORCEPROP 1 LAST BODY_TYPE PLUMBING
J 0
(-6025 1950);
DISPLAY 0.574468 (-6025 1950);
PAINT GREEN (-6025 1950);
DISPLAY INVISIBLE (-6025 1950);
FORCEPROP 1 LAST HDL_TAP TRUE
J 0
(-5700 1875);
DISPLAY 0.574468 (-5700 1875);
PAINT GREEN (-5700 1875);
DISPLAY INVISIBLE (-5700 1875);
FORCEPROP 1 LAST PATH I314
J 0
(-6027 2000);
DISPLAY 0.872340 (-6027 2000);
PAINT GREEN (-6027 2000);
DISPLAY INVISIBLE (-6027 2000);
FORCEADD TAP..6
(-6025 1900);
FORCEPROP 3 LASTPIN (-5975 1900) SIG_NAME P5E_CPU1_P3_RX_DN<12>
J 0
(-5965 1910);
DISPLAY 0.659574 (-5965 1910);
PAINT MONO (-5965 1910);
DISPLAY INVISIBLE (-5965 1910);
FORCEPROP 1 LASTPIN (-5975 1900) BN 12
J 0
(-6027 1908);
DISPLAY 0.489362 (-6027 1908);
PAINT MONO (-6027 1908);
FORCEPROP 2 LAST CDS_LIB standard
J 0
(-6025 1900);
DISPLAY INVISIBLE (-6025 1900);
FORCEPROP 1 LAST BODY_TYPE PLUMBING
J 0
(-6025 1850);
DISPLAY 0.574468 (-6025 1850);
PAINT GREEN (-6025 1850);
DISPLAY INVISIBLE (-6025 1850);
FORCEPROP 1 LAST HDL_TAP TRUE
J 0
(-5700 1775);
DISPLAY 0.574468 (-5700 1775);
PAINT GREEN (-5700 1775);
DISPLAY INVISIBLE (-5700 1775);
FORCEPROP 1 LAST PATH I315
J 0
(-6027 1900);
DISPLAY 0.872340 (-6027 1900);
PAINT GREEN (-6027 1900);
DISPLAY INVISIBLE (-6027 1900);
FORCEADD TAP..6
(-6025 1800);
FORCEPROP 3 LASTPIN (-5975 1800) SIG_NAME P5E_CPU1_P3_RX_DN<13>
J 0
(-5965 1810);
DISPLAY 0.659574 (-5965 1810);
PAINT MONO (-5965 1810);
DISPLAY INVISIBLE (-5965 1810);
FORCEPROP 1 LASTPIN (-5975 1800) BN 13
J 0
(-6027 1808);
DISPLAY 0.489362 (-6027 1808);
PAINT MONO (-6027 1808);
FORCEPROP 2 LAST CDS_LIB standard
J 0
(-6025 1800);
DISPLAY INVISIBLE (-6025 1800);
FORCEPROP 1 LAST BODY_TYPE PLUMBING
J 0
(-6025 1750);
DISPLAY 0.574468 (-6025 1750);
PAINT GREEN (-6025 1750);
DISPLAY INVISIBLE (-6025 1750);
FORCEPROP 1 LAST HDL_TAP TRUE
J 0
(-5700 1675);
DISPLAY 0.574468 (-5700 1675);
PAINT GREEN (-5700 1675);
DISPLAY INVISIBLE (-5700 1675);
FORCEPROP 1 LAST PATH I316
J 0
(-6027 1800);
DISPLAY 0.872340 (-6027 1800);
PAINT GREEN (-6027 1800);
DISPLAY INVISIBLE (-6027 1800);
FORCEADD TAP..6
(-6025 1700);
FORCEPROP 3 LASTPIN (-5975 1700) SIG_NAME P5E_CPU1_P3_RX_DN<14>
J 0
(-5965 1710);
DISPLAY 0.659574 (-5965 1710);
PAINT MONO (-5965 1710);
DISPLAY INVISIBLE (-5965 1710);
FORCEPROP 1 LASTPIN (-5975 1700) BN 14
J 0
(-6027 1708);
DISPLAY 0.489362 (-6027 1708);
PAINT MONO (-6027 1708);
FORCEPROP 2 LAST CDS_LIB standard
J 0
(-6025 1700);
DISPLAY INVISIBLE (-6025 1700);
FORCEPROP 1 LAST BODY_TYPE PLUMBING
J 0
(-6025 1650);
DISPLAY 0.574468 (-6025 1650);
PAINT GREEN (-6025 1650);
DISPLAY INVISIBLE (-6025 1650);
FORCEPROP 1 LAST HDL_TAP TRUE
J 0
(-5700 1575);
DISPLAY 0.574468 (-5700 1575);
PAINT GREEN (-5700 1575);
DISPLAY INVISIBLE (-5700 1575);
FORCEPROP 1 LAST PATH I317
J 0
(-6027 1700);
DISPLAY 0.872340 (-6027 1700);
PAINT GREEN (-6027 1700);
DISPLAY INVISIBLE (-6027 1700);
FORCEADD TAP..6
(-6025 1600);
FORCEPROP 3 LASTPIN (-5975 1600) SIG_NAME P5E_CPU1_P3_RX_DN<15>
J 0
(-5965 1610);
DISPLAY 0.659574 (-5965 1610);
PAINT MONO (-5965 1610);
DISPLAY INVISIBLE (-5965 1610);
FORCEPROP 1 LASTPIN (-5975 1600) BN 15
J 0
(-6027 1608);
DISPLAY 0.489362 (-6027 1608);
PAINT MONO (-6027 1608);
FORCEPROP 2 LAST CDS_LIB standard
J 0
(-6025 1600);
DISPLAY INVISIBLE (-6025 1600);
FORCEPROP 1 LAST BODY_TYPE PLUMBING
J 0
(-6025 1550);
DISPLAY 0.574468 (-6025 1550);
PAINT GREEN (-6025 1550);
DISPLAY INVISIBLE (-6025 1550);
FORCEPROP 1 LAST HDL_TAP TRUE
J 0
(-5700 1475);
DISPLAY 0.574468 (-5700 1475);
PAINT GREEN (-5700 1475);
DISPLAY INVISIBLE (-5700 1475);
FORCEPROP 1 LAST PATH I318
J 0
(-6027 1600);
DISPLAY 0.872340 (-6027 1600);
PAINT GREEN (-6027 1600);
DISPLAY INVISIBLE (-6027 1600);
FORCEADD OFFPAGE..1
(-7075 3375);
FORCEPROP 2 LAST $XR2 127 
J 0
(-7567 3375);
DISPLAY 0.638298 (-7567 3375);
PAINT MONO (-7567 3375);
FORCEPROP 2 LAST $XR1 126 
J 0
(-7447 3375);
DISPLAY 0.638298 (-7447 3375);
PAINT MONO (-7447 3375);
FORCEPROP 2 LAST $XR0 119 
J 0
(-7327 3375);
DISPLAY 0.638298 (-7327 3375);
PAINT MONO (-7327 3375);
FORCEPROP 2 LAST PATH I319
J 0
(-7025 3450);
DISPLAY 1.021277 (-7025 3450);
DISPLAY INVISIBLE (-7025 3450);
FORCEPROP 1 LAST COMMENT_BODY TRUE
J 0
(-6950 3275);
DISPLAY 0.872340 (-6950 3275);
PAINT GREEN (-6950 3275);
DISPLAY INVISIBLE (-6950 3275);
FORCEPROP 1 LAST OFFPAGE TRUE
J 0
(-6750 3250);
DISPLAY 0.872340 (-6750 3250);
PAINT GREEN (-6750 3250);
DISPLAY INVISIBLE (-6750 3250);
FORCEPROP 2 LAST CDS_LIB standard
J 0
(-7075 3375);
DISPLAY INVISIBLE (-7075 3375);
FORCEADD OFFPAGE..1
(-7075 3325);
FORCEPROP 2 LAST $XR2 127 
J 0
(-7567 3325);
DISPLAY 0.638298 (-7567 3325);
PAINT MONO (-7567 3325);
FORCEPROP 2 LAST $XR1 126 
J 0
(-7447 3325);
DISPLAY 0.638298 (-7447 3325);
PAINT MONO (-7447 3325);
FORCEPROP 2 LAST $XR0 119 
J 0
(-7327 3325);
DISPLAY 0.638298 (-7327 3325);
PAINT MONO (-7327 3325);
FORCEPROP 2 LAST PATH I320
J 0
(-7025 3400);
DISPLAY 1.021277 (-7025 3400);
DISPLAY INVISIBLE (-7025 3400);
FORCEPROP 1 LAST COMMENT_BODY TRUE
J 0
(-6950 3225);
DISPLAY 0.872340 (-6950 3225);
PAINT GREEN (-6950 3225);
DISPLAY INVISIBLE (-6950 3225);
FORCEPROP 1 LAST OFFPAGE TRUE
J 0
(-6750 3200);
DISPLAY 0.872340 (-6750 3200);
PAINT GREEN (-6750 3200);
DISPLAY INVISIBLE (-6750 3200);
FORCEPROP 2 LAST CDS_LIB standard
J 0
(-7075 3325);
DISPLAY INVISIBLE (-7075 3325);
FORCEADD TAP..6
(-5875 5650);
FORCEPROP 3 LASTPIN (-5825 5650) SIG_NAME P5E_CPU1_P2_RX_DP<0>
J 0
(-5815 5660);
DISPLAY 0.659574 (-5815 5660);
PAINT MONO (-5815 5660);
DISPLAY INVISIBLE (-5815 5660);
FORCEPROP 1 LASTPIN (-5825 5650) BN 0
J 0
(-5877 5658);
DISPLAY 0.489362 (-5877 5658);
PAINT MONO (-5877 5658);
FORCEPROP 2 LAST CDS_LIB mstr_standard
J 0
(-5875 5650);
DISPLAY INVISIBLE (-5875 5650);
FORCEPROP 1 LAST BODY_TYPE PLUMBING
J 0
(-5875 5600);
DISPLAY 0.574468 (-5875 5600);
PAINT GREEN (-5875 5600);
DISPLAY INVISIBLE (-5875 5600);
FORCEPROP 1 LAST HDL_TAP TRUE
J 0
(-5550 5525);
DISPLAY 0.574468 (-5550 5525);
PAINT GREEN (-5550 5525);
DISPLAY INVISIBLE (-5550 5525);
FORCEPROP 1 LAST PATH I321
J 0
(-5877 5650);
DISPLAY 0.872340 (-5877 5650);
PAINT GREEN (-5877 5650);
DISPLAY INVISIBLE (-5877 5650);
FORCEADD TAP..6
(-5875 5550);
FORCEPROP 3 LASTPIN (-5825 5550) SIG_NAME P5E_CPU1_P2_RX_DP<1>
J 0
(-5815 5560);
DISPLAY 0.659574 (-5815 5560);
PAINT MONO (-5815 5560);
DISPLAY INVISIBLE (-5815 5560);
FORCEPROP 1 LASTPIN (-5825 5550) BN 1
J 0
(-5877 5558);
DISPLAY 0.489362 (-5877 5558);
PAINT MONO (-5877 5558);
FORCEPROP 2 LAST CDS_LIB mstr_standard
J 0
(-5875 5550);
DISPLAY INVISIBLE (-5875 5550);
FORCEPROP 1 LAST BODY_TYPE PLUMBING
J 0
(-5875 5500);
DISPLAY 0.574468 (-5875 5500);
PAINT GREEN (-5875 5500);
DISPLAY INVISIBLE (-5875 5500);
FORCEPROP 1 LAST HDL_TAP TRUE
J 0
(-5550 5425);
DISPLAY 0.574468 (-5550 5425);
PAINT GREEN (-5550 5425);
DISPLAY INVISIBLE (-5550 5425);
FORCEPROP 1 LAST PATH I322
J 0
(-5877 5550);
DISPLAY 0.872340 (-5877 5550);
PAINT GREEN (-5877 5550);
DISPLAY INVISIBLE (-5877 5550);
FORCEADD TAP..6
(-5875 5450);
FORCEPROP 3 LASTPIN (-5825 5450) SIG_NAME P5E_CPU1_P2_RX_DP<2>
J 0
(-5815 5460);
DISPLAY 0.659574 (-5815 5460);
PAINT MONO (-5815 5460);
DISPLAY INVISIBLE (-5815 5460);
FORCEPROP 1 LASTPIN (-5825 5450) BN 2
J 0
(-5877 5458);
DISPLAY 0.489362 (-5877 5458);
PAINT MONO (-5877 5458);
FORCEPROP 2 LAST CDS_LIB mstr_standard
J 0
(-5875 5450);
DISPLAY INVISIBLE (-5875 5450);
FORCEPROP 1 LAST BODY_TYPE PLUMBING
J 0
(-5875 5400);
DISPLAY 0.574468 (-5875 5400);
PAINT GREEN (-5875 5400);
DISPLAY INVISIBLE (-5875 5400);
FORCEPROP 1 LAST HDL_TAP TRUE
J 0
(-5550 5325);
DISPLAY 0.574468 (-5550 5325);
PAINT GREEN (-5550 5325);
DISPLAY INVISIBLE (-5550 5325);
FORCEPROP 1 LAST PATH I323
J 0
(-5877 5450);
DISPLAY 0.872340 (-5877 5450);
PAINT GREEN (-5877 5450);
DISPLAY INVISIBLE (-5877 5450);
FORCEADD TAP..6
(-6025 5600);
FORCEPROP 3 LASTPIN (-5975 5600) SIG_NAME P5E_CPU1_P2_RX_DN<0>
J 0
(-5965 5610);
DISPLAY 0.659574 (-5965 5610);
PAINT MONO (-5965 5610);
DISPLAY INVISIBLE (-5965 5610);
FORCEPROP 1 LASTPIN (-5975 5600) BN 0
J 0
(-6027 5608);
DISPLAY 0.489362 (-6027 5608);
PAINT MONO (-6027 5608);
FORCEPROP 2 LAST CDS_LIB mstr_standard
J 0
(-6025 5600);
DISPLAY INVISIBLE (-6025 5600);
FORCEPROP 1 LAST BODY_TYPE PLUMBING
J 0
(-6025 5550);
DISPLAY 0.574468 (-6025 5550);
PAINT GREEN (-6025 5550);
DISPLAY INVISIBLE (-6025 5550);
FORCEPROP 1 LAST HDL_TAP TRUE
J 0
(-5700 5475);
DISPLAY 0.574468 (-5700 5475);
PAINT GREEN (-5700 5475);
DISPLAY INVISIBLE (-5700 5475);
FORCEPROP 1 LAST PATH I324
J 0
(-6027 5600);
DISPLAY 0.872340 (-6027 5600);
PAINT GREEN (-6027 5600);
DISPLAY INVISIBLE (-6027 5600);
FORCEADD TAP..6
(-6025 5500);
FORCEPROP 3 LASTPIN (-5975 5500) SIG_NAME P5E_CPU1_P2_RX_DN<1>
J 0
(-5965 5510);
DISPLAY 0.659574 (-5965 5510);
PAINT MONO (-5965 5510);
DISPLAY INVISIBLE (-5965 5510);
FORCEPROP 1 LASTPIN (-5975 5500) BN 1
J 0
(-6027 5508);
DISPLAY 0.489362 (-6027 5508);
PAINT MONO (-6027 5508);
FORCEPROP 2 LAST CDS_LIB mstr_standard
J 0
(-6025 5500);
DISPLAY INVISIBLE (-6025 5500);
FORCEPROP 1 LAST BODY_TYPE PLUMBING
J 0
(-6025 5450);
DISPLAY 0.574468 (-6025 5450);
PAINT GREEN (-6025 5450);
DISPLAY INVISIBLE (-6025 5450);
FORCEPROP 1 LAST HDL_TAP TRUE
J 0
(-5700 5375);
DISPLAY 0.574468 (-5700 5375);
PAINT GREEN (-5700 5375);
DISPLAY INVISIBLE (-5700 5375);
FORCEPROP 1 LAST PATH I325
J 0
(-6027 5500);
DISPLAY 0.872340 (-6027 5500);
PAINT GREEN (-6027 5500);
DISPLAY INVISIBLE (-6027 5500);
FORCEADD TAP..6
(-6025 5400);
FORCEPROP 3 LASTPIN (-5975 5400) SIG_NAME P5E_CPU1_P2_RX_DN<2>
J 0
(-5965 5410);
DISPLAY 0.659574 (-5965 5410);
PAINT MONO (-5965 5410);
DISPLAY INVISIBLE (-5965 5410);
FORCEPROP 1 LASTPIN (-5975 5400) BN 2
J 0
(-6027 5408);
DISPLAY 0.489362 (-6027 5408);
PAINT MONO (-6027 5408);
FORCEPROP 2 LAST CDS_LIB standard
J 0
(-6025 5400);
DISPLAY INVISIBLE (-6025 5400);
FORCEPROP 1 LAST BODY_TYPE PLUMBING
J 0
(-6025 5350);
DISPLAY 0.574468 (-6025 5350);
PAINT GREEN (-6025 5350);
DISPLAY INVISIBLE (-6025 5350);
FORCEPROP 1 LAST HDL_TAP TRUE
J 0
(-5700 5275);
DISPLAY 0.574468 (-5700 5275);
PAINT GREEN (-5700 5275);
DISPLAY INVISIBLE (-5700 5275);
FORCEPROP 1 LAST PATH I326
J 0
(-6027 5400);
DISPLAY 0.872340 (-6027 5400);
PAINT GREEN (-6027 5400);
DISPLAY INVISIBLE (-6027 5400);
FORCEADD TAP..6
(-5875 5150);
FORCEPROP 3 LASTPIN (-5825 5150) SIG_NAME P5E_CPU1_P2_RX_DP<5>
J 0
(-5815 5160);
DISPLAY 0.659574 (-5815 5160);
PAINT MONO (-5815 5160);
DISPLAY INVISIBLE (-5815 5160);
FORCEPROP 1 LASTPIN (-5825 5150) BN 5
J 0
(-5877 5158);
DISPLAY 0.489362 (-5877 5158);
PAINT MONO (-5877 5158);
FORCEPROP 2 LAST CDS_LIB standard
J 0
(-5875 5150);
DISPLAY INVISIBLE (-5875 5150);
FORCEPROP 1 LAST BODY_TYPE PLUMBING
J 0
(-5875 5100);
DISPLAY 0.574468 (-5875 5100);
PAINT GREEN (-5875 5100);
DISPLAY INVISIBLE (-5875 5100);
FORCEPROP 1 LAST HDL_TAP TRUE
J 0
(-5550 5025);
DISPLAY 0.574468 (-5550 5025);
PAINT GREEN (-5550 5025);
DISPLAY INVISIBLE (-5550 5025);
FORCEPROP 1 LAST PATH I327
J 0
(-5877 5150);
DISPLAY 0.872340 (-5877 5150);
PAINT GREEN (-5877 5150);
DISPLAY INVISIBLE (-5877 5150);
FORCEADD TAP..6
(-5875 5350);
FORCEPROP 3 LASTPIN (-5825 5350) SIG_NAME P5E_CPU1_P2_RX_DP<3>
J 0
(-5815 5360);
DISPLAY 0.659574 (-5815 5360);
PAINT MONO (-5815 5360);
DISPLAY INVISIBLE (-5815 5360);
FORCEPROP 1 LASTPIN (-5825 5350) BN 3
J 0
(-5877 5358);
DISPLAY 0.489362 (-5877 5358);
PAINT MONO (-5877 5358);
FORCEPROP 2 LAST CDS_LIB standard
J 0
(-5875 5350);
DISPLAY INVISIBLE (-5875 5350);
FORCEPROP 1 LAST BODY_TYPE PLUMBING
J 0
(-5875 5300);
DISPLAY 0.574468 (-5875 5300);
PAINT GREEN (-5875 5300);
DISPLAY INVISIBLE (-5875 5300);
FORCEPROP 1 LAST HDL_TAP TRUE
J 0
(-5550 5225);
DISPLAY 0.574468 (-5550 5225);
PAINT GREEN (-5550 5225);
DISPLAY INVISIBLE (-5550 5225);
FORCEPROP 1 LAST PATH I328
J 0
(-5877 5350);
DISPLAY 0.872340 (-5877 5350);
PAINT GREEN (-5877 5350);
DISPLAY INVISIBLE (-5877 5350);
FORCEADD TAP..6
(-5875 5250);
FORCEPROP 3 LASTPIN (-5825 5250) SIG_NAME P5E_CPU1_P2_RX_DP<4>
J 0
(-5815 5260);
DISPLAY 0.659574 (-5815 5260);
PAINT MONO (-5815 5260);
DISPLAY INVISIBLE (-5815 5260);
FORCEPROP 1 LASTPIN (-5825 5250) BN 4
J 0
(-5877 5258);
DISPLAY 0.489362 (-5877 5258);
PAINT MONO (-5877 5258);
FORCEPROP 2 LAST CDS_LIB standard
J 0
(-5875 5250);
DISPLAY INVISIBLE (-5875 5250);
FORCEPROP 1 LAST BODY_TYPE PLUMBING
J 0
(-5875 5200);
DISPLAY 0.574468 (-5875 5200);
PAINT GREEN (-5875 5200);
DISPLAY INVISIBLE (-5875 5200);
FORCEPROP 1 LAST HDL_TAP TRUE
J 0
(-5550 5125);
DISPLAY 0.574468 (-5550 5125);
PAINT GREEN (-5550 5125);
DISPLAY INVISIBLE (-5550 5125);
FORCEPROP 1 LAST PATH I329
J 0
(-5877 5250);
DISPLAY 0.872340 (-5877 5250);
PAINT GREEN (-5877 5250);
DISPLAY INVISIBLE (-5877 5250);
FORCEADD TAP..6
(-6025 5200);
FORCEPROP 3 LASTPIN (-5975 5200) SIG_NAME P5E_CPU1_P2_RX_DN<4>
J 0
(-5965 5210);
DISPLAY 0.659574 (-5965 5210);
PAINT MONO (-5965 5210);
DISPLAY INVISIBLE (-5965 5210);
FORCEPROP 1 LASTPIN (-5975 5200) BN 4
J 0
(-6027 5208);
DISPLAY 0.489362 (-6027 5208);
PAINT MONO (-6027 5208);
FORCEPROP 2 LAST CDS_LIB standard
J 0
(-6025 5200);
DISPLAY INVISIBLE (-6025 5200);
FORCEPROP 1 LAST BODY_TYPE PLUMBING
J 0
(-6025 5150);
DISPLAY 0.574468 (-6025 5150);
PAINT GREEN (-6025 5150);
DISPLAY INVISIBLE (-6025 5150);
FORCEPROP 1 LAST HDL_TAP TRUE
J 0
(-5700 5075);
DISPLAY 0.574468 (-5700 5075);
PAINT GREEN (-5700 5075);
DISPLAY INVISIBLE (-5700 5075);
FORCEPROP 1 LAST PATH I330
J 0
(-6027 5200);
DISPLAY 0.872340 (-6027 5200);
PAINT GREEN (-6027 5200);
DISPLAY INVISIBLE (-6027 5200);
FORCEADD TAP..6
(-6025 5300);
FORCEPROP 3 LASTPIN (-5975 5300) SIG_NAME P5E_CPU1_P2_RX_DN<3>
J 0
(-5965 5310);
DISPLAY 0.659574 (-5965 5310);
PAINT MONO (-5965 5310);
DISPLAY INVISIBLE (-5965 5310);
FORCEPROP 1 LASTPIN (-5975 5300) BN 3
J 0
(-6027 5308);
DISPLAY 0.489362 (-6027 5308);
PAINT MONO (-6027 5308);
FORCEPROP 2 LAST CDS_LIB standard
J 0
(-6025 5300);
DISPLAY INVISIBLE (-6025 5300);
FORCEPROP 1 LAST BODY_TYPE PLUMBING
J 0
(-6025 5250);
DISPLAY 0.574468 (-6025 5250);
PAINT GREEN (-6025 5250);
DISPLAY INVISIBLE (-6025 5250);
FORCEPROP 1 LAST HDL_TAP TRUE
J 0
(-5700 5175);
DISPLAY 0.574468 (-5700 5175);
PAINT GREEN (-5700 5175);
DISPLAY INVISIBLE (-5700 5175);
FORCEPROP 1 LAST PATH I331
J 0
(-6027 5300);
DISPLAY 0.872340 (-6027 5300);
PAINT GREEN (-6027 5300);
DISPLAY INVISIBLE (-6027 5300);
FORCEADD TAP..6
(-5875 5050);
FORCEPROP 3 LASTPIN (-5825 5050) SIG_NAME P5E_CPU1_P2_RX_DP<6>
J 0
(-5815 5060);
DISPLAY 0.659574 (-5815 5060);
PAINT MONO (-5815 5060);
DISPLAY INVISIBLE (-5815 5060);
FORCEPROP 1 LASTPIN (-5825 5050) BN 6
J 0
(-5877 5058);
DISPLAY 0.489362 (-5877 5058);
PAINT MONO (-5877 5058);
FORCEPROP 2 LAST CDS_LIB standard
J 0
(-5875 5050);
DISPLAY INVISIBLE (-5875 5050);
FORCEPROP 1 LAST BODY_TYPE PLUMBING
J 0
(-5875 5000);
DISPLAY 0.574468 (-5875 5000);
PAINT GREEN (-5875 5000);
DISPLAY INVISIBLE (-5875 5000);
FORCEPROP 1 LAST HDL_TAP TRUE
J 0
(-5550 4925);
DISPLAY 0.574468 (-5550 4925);
PAINT GREEN (-5550 4925);
DISPLAY INVISIBLE (-5550 4925);
FORCEPROP 1 LAST PATH I332
J 0
(-5877 5050);
DISPLAY 0.872340 (-5877 5050);
PAINT GREEN (-5877 5050);
DISPLAY INVISIBLE (-5877 5050);
FORCEADD TAP..6
(-5875 4850);
FORCEPROP 3 LASTPIN (-5825 4850) SIG_NAME P5E_CPU1_P2_RX_DP<8>
J 0
(-5815 4860);
DISPLAY 0.659574 (-5815 4860);
PAINT MONO (-5815 4860);
DISPLAY INVISIBLE (-5815 4860);
FORCEPROP 1 LASTPIN (-5825 4850) BN 8
J 0
(-5877 4858);
DISPLAY 0.489362 (-5877 4858);
PAINT MONO (-5877 4858);
FORCEPROP 2 LAST CDS_LIB standard
J 0
(-5875 4850);
DISPLAY INVISIBLE (-5875 4850);
FORCEPROP 1 LAST BODY_TYPE PLUMBING
J 0
(-5875 4800);
DISPLAY 0.574468 (-5875 4800);
PAINT GREEN (-5875 4800);
DISPLAY INVISIBLE (-5875 4800);
FORCEPROP 1 LAST HDL_TAP TRUE
J 0
(-5550 4725);
DISPLAY 0.574468 (-5550 4725);
PAINT GREEN (-5550 4725);
DISPLAY INVISIBLE (-5550 4725);
FORCEPROP 1 LAST PATH I333
J 0
(-5877 4850);
DISPLAY 0.872340 (-5877 4850);
PAINT GREEN (-5877 4850);
DISPLAY INVISIBLE (-5877 4850);
FORCEADD TAP..6
(-5875 4950);
FORCEPROP 3 LASTPIN (-5825 4950) SIG_NAME P5E_CPU1_P2_RX_DP<7>
J 0
(-5815 4960);
DISPLAY 0.659574 (-5815 4960);
PAINT MONO (-5815 4960);
DISPLAY INVISIBLE (-5815 4960);
FORCEPROP 1 LASTPIN (-5825 4950) BN 7
J 0
(-5877 4958);
DISPLAY 0.489362 (-5877 4958);
PAINT MONO (-5877 4958);
FORCEPROP 2 LAST CDS_LIB standard
J 0
(-5875 4950);
DISPLAY INVISIBLE (-5875 4950);
FORCEPROP 1 LAST BODY_TYPE PLUMBING
J 0
(-5875 4900);
DISPLAY 0.574468 (-5875 4900);
PAINT GREEN (-5875 4900);
DISPLAY INVISIBLE (-5875 4900);
FORCEPROP 1 LAST HDL_TAP TRUE
J 0
(-5550 4825);
DISPLAY 0.574468 (-5550 4825);
PAINT GREEN (-5550 4825);
DISPLAY INVISIBLE (-5550 4825);
FORCEPROP 1 LAST PATH I334
J 0
(-5877 4950);
DISPLAY 0.872340 (-5877 4950);
PAINT GREEN (-5877 4950);
DISPLAY INVISIBLE (-5877 4950);
FORCEADD TAP..6
(-6025 4900);
FORCEPROP 3 LASTPIN (-5975 4900) SIG_NAME P5E_CPU1_P2_RX_DN<7>
J 0
(-5965 4910);
DISPLAY 0.659574 (-5965 4910);
PAINT MONO (-5965 4910);
DISPLAY INVISIBLE (-5965 4910);
FORCEPROP 1 LASTPIN (-5975 4900) BN 7
J 0
(-6027 4908);
DISPLAY 0.489362 (-6027 4908);
PAINT MONO (-6027 4908);
FORCEPROP 2 LAST CDS_LIB standard
J 0
(-6025 4900);
DISPLAY INVISIBLE (-6025 4900);
FORCEPROP 1 LAST BODY_TYPE PLUMBING
J 0
(-6025 4850);
DISPLAY 0.574468 (-6025 4850);
PAINT GREEN (-6025 4850);
DISPLAY INVISIBLE (-6025 4850);
FORCEPROP 1 LAST HDL_TAP TRUE
J 0
(-5700 4775);
DISPLAY 0.574468 (-5700 4775);
PAINT GREEN (-5700 4775);
DISPLAY INVISIBLE (-5700 4775);
FORCEPROP 1 LAST PATH I335
J 0
(-6027 4900);
DISPLAY 0.872340 (-6027 4900);
PAINT GREEN (-6027 4900);
DISPLAY INVISIBLE (-6027 4900);
FORCEADD TAP..6
(-6025 5000);
FORCEPROP 3 LASTPIN (-5975 5000) SIG_NAME P5E_CPU1_P2_RX_DN<6>
J 0
(-5965 5010);
DISPLAY 0.659574 (-5965 5010);
PAINT MONO (-5965 5010);
DISPLAY INVISIBLE (-5965 5010);
FORCEPROP 1 LASTPIN (-5975 5000) BN 6
J 0
(-6027 5008);
DISPLAY 0.489362 (-6027 5008);
PAINT MONO (-6027 5008);
FORCEPROP 2 LAST CDS_LIB standard
J 0
(-6025 5000);
DISPLAY INVISIBLE (-6025 5000);
FORCEPROP 1 LAST BODY_TYPE PLUMBING
J 0
(-6025 4950);
DISPLAY 0.574468 (-6025 4950);
PAINT GREEN (-6025 4950);
DISPLAY INVISIBLE (-6025 4950);
FORCEPROP 1 LAST HDL_TAP TRUE
J 0
(-5700 4875);
DISPLAY 0.574468 (-5700 4875);
PAINT GREEN (-5700 4875);
DISPLAY INVISIBLE (-5700 4875);
FORCEPROP 1 LAST PATH I336
J 0
(-6027 5000);
DISPLAY 0.872340 (-6027 5000);
PAINT GREEN (-6027 5000);
DISPLAY INVISIBLE (-6027 5000);
FORCEADD TAP..6
(-6025 5100);
FORCEPROP 3 LASTPIN (-5975 5100) SIG_NAME P5E_CPU1_P2_RX_DN<5>
J 0
(-5965 5110);
DISPLAY 0.659574 (-5965 5110);
PAINT MONO (-5965 5110);
DISPLAY INVISIBLE (-5965 5110);
FORCEPROP 1 LASTPIN (-5975 5100) BN 5
J 0
(-6027 5108);
DISPLAY 0.489362 (-6027 5108);
PAINT MONO (-6027 5108);
FORCEPROP 2 LAST CDS_LIB standard
J 0
(-6025 5100);
DISPLAY INVISIBLE (-6025 5100);
FORCEPROP 1 LAST BODY_TYPE PLUMBING
J 0
(-6025 5050);
DISPLAY 0.574468 (-6025 5050);
PAINT GREEN (-6025 5050);
DISPLAY INVISIBLE (-6025 5050);
FORCEPROP 1 LAST HDL_TAP TRUE
J 0
(-5700 4975);
DISPLAY 0.574468 (-5700 4975);
PAINT GREEN (-5700 4975);
DISPLAY INVISIBLE (-5700 4975);
FORCEPROP 1 LAST PATH I337
J 0
(-6027 5100);
DISPLAY 0.872340 (-6027 5100);
PAINT GREEN (-6027 5100);
DISPLAY INVISIBLE (-6027 5100);
FORCEADD TAP..6
(-5875 4750);
FORCEPROP 3 LASTPIN (-5825 4750) SIG_NAME P5E_CPU1_P2_RX_DP<9>
J 0
(-5815 4760);
DISPLAY 0.659574 (-5815 4760);
PAINT MONO (-5815 4760);
DISPLAY INVISIBLE (-5815 4760);
FORCEPROP 1 LASTPIN (-5825 4750) BN 9
J 0
(-5877 4758);
DISPLAY 0.489362 (-5877 4758);
PAINT MONO (-5877 4758);
FORCEPROP 2 LAST CDS_LIB standard
J 0
(-5875 4750);
DISPLAY INVISIBLE (-5875 4750);
FORCEPROP 1 LAST BODY_TYPE PLUMBING
J 0
(-5875 4700);
DISPLAY 0.574468 (-5875 4700);
PAINT GREEN (-5875 4700);
DISPLAY INVISIBLE (-5875 4700);
FORCEPROP 1 LAST HDL_TAP TRUE
J 0
(-5550 4625);
DISPLAY 0.574468 (-5550 4625);
PAINT GREEN (-5550 4625);
DISPLAY INVISIBLE (-5550 4625);
FORCEPROP 1 LAST PATH I338
J 0
(-5877 4750);
DISPLAY 0.872340 (-5877 4750);
PAINT GREEN (-5877 4750);
DISPLAY INVISIBLE (-5877 4750);
FORCEADD TAP..6
(-5875 4650);
FORCEPROP 3 LASTPIN (-5825 4650) SIG_NAME P5E_CPU1_P2_RX_DP<10>
J 0
(-5815 4660);
DISPLAY 0.659574 (-5815 4660);
PAINT MONO (-5815 4660);
DISPLAY INVISIBLE (-5815 4660);
FORCEPROP 1 LASTPIN (-5825 4650) BN 10
J 0
(-5877 4658);
DISPLAY 0.489362 (-5877 4658);
PAINT MONO (-5877 4658);
FORCEPROP 2 LAST CDS_LIB standard
J 0
(-5875 4650);
DISPLAY INVISIBLE (-5875 4650);
FORCEPROP 1 LAST BODY_TYPE PLUMBING
J 0
(-5875 4600);
DISPLAY 0.574468 (-5875 4600);
PAINT GREEN (-5875 4600);
DISPLAY INVISIBLE (-5875 4600);
FORCEPROP 1 LAST HDL_TAP TRUE
J 0
(-5550 4525);
DISPLAY 0.574468 (-5550 4525);
PAINT GREEN (-5550 4525);
DISPLAY INVISIBLE (-5550 4525);
FORCEPROP 1 LAST PATH I339
J 0
(-5877 4650);
DISPLAY 0.872340 (-5877 4650);
PAINT GREEN (-5877 4650);
DISPLAY INVISIBLE (-5877 4650);
FORCEADD TAP..6
(-6025 4700);
FORCEPROP 3 LASTPIN (-5975 4700) SIG_NAME P5E_CPU1_P2_RX_DN<9>
J 0
(-5965 4710);
DISPLAY 0.659574 (-5965 4710);
PAINT MONO (-5965 4710);
DISPLAY INVISIBLE (-5965 4710);
FORCEPROP 1 LASTPIN (-5975 4700) BN 9
J 0
(-6027 4708);
DISPLAY 0.489362 (-6027 4708);
PAINT MONO (-6027 4708);
FORCEPROP 2 LAST CDS_LIB standard
J 0
(-6025 4700);
DISPLAY INVISIBLE (-6025 4700);
FORCEPROP 1 LAST BODY_TYPE PLUMBING
J 0
(-6025 4650);
DISPLAY 0.574468 (-6025 4650);
PAINT GREEN (-6025 4650);
DISPLAY INVISIBLE (-6025 4650);
FORCEPROP 1 LAST HDL_TAP TRUE
J 0
(-5700 4575);
DISPLAY 0.574468 (-5700 4575);
PAINT GREEN (-5700 4575);
DISPLAY INVISIBLE (-5700 4575);
FORCEPROP 1 LAST PATH I340
J 0
(-6027 4700);
DISPLAY 0.872340 (-6027 4700);
PAINT GREEN (-6027 4700);
DISPLAY INVISIBLE (-6027 4700);
FORCEADD TAP..6
(-6025 4800);
FORCEPROP 3 LASTPIN (-5975 4800) SIG_NAME P5E_CPU1_P2_RX_DN<8>
J 0
(-5965 4810);
DISPLAY 0.659574 (-5965 4810);
PAINT MONO (-5965 4810);
DISPLAY INVISIBLE (-5965 4810);
FORCEPROP 1 LASTPIN (-5975 4800) BN 8
J 0
(-6027 4808);
DISPLAY 0.489362 (-6027 4808);
PAINT MONO (-6027 4808);
FORCEPROP 2 LAST CDS_LIB standard
J 0
(-6025 4800);
DISPLAY INVISIBLE (-6025 4800);
FORCEPROP 1 LAST BODY_TYPE PLUMBING
J 0
(-6025 4750);
DISPLAY 0.574468 (-6025 4750);
PAINT GREEN (-6025 4750);
DISPLAY INVISIBLE (-6025 4750);
FORCEPROP 1 LAST HDL_TAP TRUE
J 0
(-5700 4675);
DISPLAY 0.574468 (-5700 4675);
PAINT GREEN (-5700 4675);
DISPLAY INVISIBLE (-5700 4675);
FORCEPROP 1 LAST PATH I341
J 0
(-6027 4800);
DISPLAY 0.872340 (-6027 4800);
PAINT GREEN (-6027 4800);
DISPLAY INVISIBLE (-6027 4800);
FORCEADD TAP..6
(-5875 4550);
FORCEPROP 3 LASTPIN (-5825 4550) SIG_NAME P5E_CPU1_P2_RX_DP<11>
J 0
(-5815 4560);
DISPLAY 0.659574 (-5815 4560);
PAINT MONO (-5815 4560);
DISPLAY INVISIBLE (-5815 4560);
FORCEPROP 1 LASTPIN (-5825 4550) BN 11
J 0
(-5877 4558);
DISPLAY 0.489362 (-5877 4558);
PAINT MONO (-5877 4558);
FORCEPROP 2 LAST CDS_LIB standard
J 0
(-5875 4550);
DISPLAY INVISIBLE (-5875 4550);
FORCEPROP 1 LAST BODY_TYPE PLUMBING
J 0
(-5875 4500);
DISPLAY 0.574468 (-5875 4500);
PAINT GREEN (-5875 4500);
DISPLAY INVISIBLE (-5875 4500);
FORCEPROP 1 LAST HDL_TAP TRUE
J 0
(-5550 4425);
DISPLAY 0.574468 (-5550 4425);
PAINT GREEN (-5550 4425);
DISPLAY INVISIBLE (-5550 4425);
FORCEPROP 1 LAST PATH I342
J 0
(-5877 4550);
DISPLAY 0.872340 (-5877 4550);
PAINT GREEN (-5877 4550);
DISPLAY INVISIBLE (-5877 4550);
FORCEADD TAP..6
(-5875 4350);
FORCEPROP 3 LASTPIN (-5825 4350) SIG_NAME P5E_CPU1_P2_RX_DP<13>
J 0
(-5815 4360);
DISPLAY 0.659574 (-5815 4360);
PAINT MONO (-5815 4360);
DISPLAY INVISIBLE (-5815 4360);
FORCEPROP 1 LASTPIN (-5825 4350) BN 13
J 0
(-5877 4358);
DISPLAY 0.489362 (-5877 4358);
PAINT MONO (-5877 4358);
FORCEPROP 2 LAST CDS_LIB standard
J 0
(-5875 4350);
DISPLAY INVISIBLE (-5875 4350);
FORCEPROP 1 LAST BODY_TYPE PLUMBING
J 0
(-5875 4300);
DISPLAY 0.574468 (-5875 4300);
PAINT GREEN (-5875 4300);
DISPLAY INVISIBLE (-5875 4300);
FORCEPROP 1 LAST HDL_TAP TRUE
J 0
(-5550 4225);
DISPLAY 0.574468 (-5550 4225);
PAINT GREEN (-5550 4225);
DISPLAY INVISIBLE (-5550 4225);
FORCEPROP 1 LAST PATH I343
J 0
(-5877 4350);
DISPLAY 0.872340 (-5877 4350);
PAINT GREEN (-5877 4350);
DISPLAY INVISIBLE (-5877 4350);
FORCEADD TAP..6
(-5875 4450);
FORCEPROP 3 LASTPIN (-5825 4450) SIG_NAME P5E_CPU1_P2_RX_DP<12>
J 0
(-5815 4460);
DISPLAY 0.659574 (-5815 4460);
PAINT MONO (-5815 4460);
DISPLAY INVISIBLE (-5815 4460);
FORCEPROP 1 LASTPIN (-5825 4450) BN 12
J 0
(-5877 4458);
DISPLAY 0.489362 (-5877 4458);
PAINT MONO (-5877 4458);
FORCEPROP 2 LAST CDS_LIB standard
J 0
(-5875 4450);
DISPLAY INVISIBLE (-5875 4450);
FORCEPROP 1 LAST BODY_TYPE PLUMBING
J 0
(-5875 4400);
DISPLAY 0.574468 (-5875 4400);
PAINT GREEN (-5875 4400);
DISPLAY INVISIBLE (-5875 4400);
FORCEPROP 1 LAST HDL_TAP TRUE
J 0
(-5550 4325);
DISPLAY 0.574468 (-5550 4325);
PAINT GREEN (-5550 4325);
DISPLAY INVISIBLE (-5550 4325);
FORCEPROP 1 LAST PATH I344
J 0
(-5877 4450);
DISPLAY 0.872340 (-5877 4450);
PAINT GREEN (-5877 4450);
DISPLAY INVISIBLE (-5877 4450);
FORCEADD TAP..6
(-6025 4400);
FORCEPROP 3 LASTPIN (-5975 4400) SIG_NAME P5E_CPU1_P2_RX_DN<12>
J 0
(-5965 4410);
DISPLAY 0.659574 (-5965 4410);
PAINT MONO (-5965 4410);
DISPLAY INVISIBLE (-5965 4410);
FORCEPROP 1 LASTPIN (-5975 4400) BN 12
J 0
(-6027 4408);
DISPLAY 0.489362 (-6027 4408);
PAINT MONO (-6027 4408);
FORCEPROP 2 LAST CDS_LIB standard
J 0
(-6025 4400);
DISPLAY INVISIBLE (-6025 4400);
FORCEPROP 1 LAST BODY_TYPE PLUMBING
J 0
(-6025 4350);
DISPLAY 0.574468 (-6025 4350);
PAINT GREEN (-6025 4350);
DISPLAY INVISIBLE (-6025 4350);
FORCEPROP 1 LAST HDL_TAP TRUE
J 0
(-5700 4275);
DISPLAY 0.574468 (-5700 4275);
PAINT GREEN (-5700 4275);
DISPLAY INVISIBLE (-5700 4275);
FORCEPROP 1 LAST PATH I345
J 0
(-6027 4400);
DISPLAY 0.872340 (-6027 4400);
PAINT GREEN (-6027 4400);
DISPLAY INVISIBLE (-6027 4400);
FORCEADD TAP..6
(-6025 4500);
FORCEPROP 3 LASTPIN (-5975 4500) SIG_NAME P5E_CPU1_P2_RX_DN<11>
J 0
(-5965 4510);
DISPLAY 0.659574 (-5965 4510);
PAINT MONO (-5965 4510);
DISPLAY INVISIBLE (-5965 4510);
FORCEPROP 1 LASTPIN (-5975 4500) BN 11
J 0
(-6027 4508);
DISPLAY 0.489362 (-6027 4508);
PAINT MONO (-6027 4508);
FORCEPROP 2 LAST CDS_LIB standard
J 0
(-6025 4500);
DISPLAY INVISIBLE (-6025 4500);
FORCEPROP 1 LAST BODY_TYPE PLUMBING
J 0
(-6025 4450);
DISPLAY 0.574468 (-6025 4450);
PAINT GREEN (-6025 4450);
DISPLAY INVISIBLE (-6025 4450);
FORCEPROP 1 LAST HDL_TAP TRUE
J 0
(-5700 4375);
DISPLAY 0.574468 (-5700 4375);
PAINT GREEN (-5700 4375);
DISPLAY INVISIBLE (-5700 4375);
FORCEPROP 1 LAST PATH I346
J 0
(-6027 4500);
DISPLAY 0.872340 (-6027 4500);
PAINT GREEN (-6027 4500);
DISPLAY INVISIBLE (-6027 4500);
FORCEADD TAP..6
(-6025 4600);
FORCEPROP 3 LASTPIN (-5975 4600) SIG_NAME P5E_CPU1_P2_RX_DN<10>
J 0
(-5965 4610);
DISPLAY 0.659574 (-5965 4610);
PAINT MONO (-5965 4610);
DISPLAY INVISIBLE (-5965 4610);
FORCEPROP 1 LASTPIN (-5975 4600) BN 10
J 0
(-6027 4608);
DISPLAY 0.489362 (-6027 4608);
PAINT MONO (-6027 4608);
FORCEPROP 2 LAST CDS_LIB standard
J 0
(-6025 4600);
DISPLAY INVISIBLE (-6025 4600);
FORCEPROP 1 LAST BODY_TYPE PLUMBING
J 0
(-6025 4550);
DISPLAY 0.574468 (-6025 4550);
PAINT GREEN (-6025 4550);
DISPLAY INVISIBLE (-6025 4550);
FORCEPROP 1 LAST HDL_TAP TRUE
J 0
(-5700 4475);
DISPLAY 0.574468 (-5700 4475);
PAINT GREEN (-5700 4475);
DISPLAY INVISIBLE (-5700 4475);
FORCEPROP 1 LAST PATH I347
J 0
(-6027 4600);
DISPLAY 0.872340 (-6027 4600);
PAINT GREEN (-6027 4600);
DISPLAY INVISIBLE (-6027 4600);
FORCEADD TAP..6
(-5875 4250);
FORCEPROP 3 LASTPIN (-5825 4250) SIG_NAME P5E_CPU1_P2_RX_DP<14>
J 0
(-5815 4260);
DISPLAY 0.659574 (-5815 4260);
PAINT MONO (-5815 4260);
DISPLAY INVISIBLE (-5815 4260);
FORCEPROP 1 LASTPIN (-5825 4250) BN 14
J 0
(-5877 4258);
DISPLAY 0.489362 (-5877 4258);
PAINT MONO (-5877 4258);
FORCEPROP 2 LAST CDS_LIB standard
J 0
(-5875 4250);
DISPLAY INVISIBLE (-5875 4250);
FORCEPROP 1 LAST BODY_TYPE PLUMBING
J 0
(-5875 4200);
DISPLAY 0.574468 (-5875 4200);
PAINT GREEN (-5875 4200);
DISPLAY INVISIBLE (-5875 4200);
FORCEPROP 1 LAST HDL_TAP TRUE
J 0
(-5550 4125);
DISPLAY 0.574468 (-5550 4125);
PAINT GREEN (-5550 4125);
DISPLAY INVISIBLE (-5550 4125);
FORCEPROP 1 LAST PATH I348
J 0
(-5877 4250);
DISPLAY 0.872340 (-5877 4250);
PAINT GREEN (-5877 4250);
DISPLAY INVISIBLE (-5877 4250);
FORCEADD TAP..6
(-5875 4150);
FORCEPROP 3 LASTPIN (-5825 4150) SIG_NAME P5E_CPU1_P2_RX_DP<15>
J 0
(-5815 4160);
DISPLAY 0.659574 (-5815 4160);
PAINT MONO (-5815 4160);
DISPLAY INVISIBLE (-5815 4160);
FORCEPROP 1 LASTPIN (-5825 4150) BN 15
J 0
(-5877 4158);
DISPLAY 0.489362 (-5877 4158);
PAINT MONO (-5877 4158);
FORCEPROP 2 LAST CDS_LIB standard
J 0
(-5875 4150);
DISPLAY INVISIBLE (-5875 4150);
FORCEPROP 1 LAST BODY_TYPE PLUMBING
J 0
(-5875 4100);
DISPLAY 0.574468 (-5875 4100);
PAINT GREEN (-5875 4100);
DISPLAY INVISIBLE (-5875 4100);
FORCEPROP 1 LAST HDL_TAP TRUE
J 0
(-5550 4025);
DISPLAY 0.574468 (-5550 4025);
PAINT GREEN (-5550 4025);
DISPLAY INVISIBLE (-5550 4025);
FORCEPROP 1 LAST PATH I349
J 0
(-5877 4150);
DISPLAY 0.872340 (-5877 4150);
PAINT GREEN (-5877 4150);
DISPLAY INVISIBLE (-5877 4150);
FORCEADD TAP..6
(-6025 4300);
FORCEPROP 3 LASTPIN (-5975 4300) SIG_NAME P5E_CPU1_P2_RX_DN<13>
J 0
(-5965 4310);
DISPLAY 0.659574 (-5965 4310);
PAINT MONO (-5965 4310);
DISPLAY INVISIBLE (-5965 4310);
FORCEPROP 1 LASTPIN (-5975 4300) BN 13
J 0
(-6027 4308);
DISPLAY 0.489362 (-6027 4308);
PAINT MONO (-6027 4308);
FORCEPROP 2 LAST CDS_LIB standard
J 0
(-6025 4300);
DISPLAY INVISIBLE (-6025 4300);
FORCEPROP 1 LAST BODY_TYPE PLUMBING
J 0
(-6025 4250);
DISPLAY 0.574468 (-6025 4250);
PAINT GREEN (-6025 4250);
DISPLAY INVISIBLE (-6025 4250);
FORCEPROP 1 LAST HDL_TAP TRUE
J 0
(-5700 4175);
DISPLAY 0.574468 (-5700 4175);
PAINT GREEN (-5700 4175);
DISPLAY INVISIBLE (-5700 4175);
FORCEPROP 1 LAST PATH I350
J 0
(-6027 4300);
DISPLAY 0.872340 (-6027 4300);
PAINT GREEN (-6027 4300);
DISPLAY INVISIBLE (-6027 4300);
FORCEADD TAP..6
(-6025 4100);
FORCEPROP 3 LASTPIN (-5975 4100) SIG_NAME P5E_CPU1_P2_RX_DN<15>
J 0
(-5965 4110);
DISPLAY 0.659574 (-5965 4110);
PAINT MONO (-5965 4110);
DISPLAY INVISIBLE (-5965 4110);
FORCEPROP 1 LASTPIN (-5975 4100) BN 15
J 0
(-6027 4108);
DISPLAY 0.489362 (-6027 4108);
PAINT MONO (-6027 4108);
FORCEPROP 2 LAST CDS_LIB standard
J 0
(-6025 4100);
DISPLAY INVISIBLE (-6025 4100);
FORCEPROP 1 LAST BODY_TYPE PLUMBING
J 0
(-6025 4050);
DISPLAY 0.574468 (-6025 4050);
PAINT GREEN (-6025 4050);
DISPLAY INVISIBLE (-6025 4050);
FORCEPROP 1 LAST HDL_TAP TRUE
J 0
(-5700 3975);
DISPLAY 0.574468 (-5700 3975);
PAINT GREEN (-5700 3975);
DISPLAY INVISIBLE (-5700 3975);
FORCEPROP 1 LAST PATH I351
J 0
(-6027 4100);
DISPLAY 0.872340 (-6027 4100);
PAINT GREEN (-6027 4100);
DISPLAY INVISIBLE (-6027 4100);
FORCEADD TAP..6
(-6025 4200);
FORCEPROP 3 LASTPIN (-5975 4200) SIG_NAME P5E_CPU1_P2_RX_DN<14>
J 0
(-5965 4210);
DISPLAY 0.659574 (-5965 4210);
PAINT MONO (-5965 4210);
DISPLAY INVISIBLE (-5965 4210);
FORCEPROP 1 LASTPIN (-5975 4200) BN 14
J 0
(-6027 4208);
DISPLAY 0.489362 (-6027 4208);
PAINT MONO (-6027 4208);
FORCEPROP 2 LAST CDS_LIB standard
J 0
(-6025 4200);
DISPLAY INVISIBLE (-6025 4200);
FORCEPROP 1 LAST BODY_TYPE PLUMBING
J 0
(-6025 4150);
DISPLAY 0.574468 (-6025 4150);
PAINT GREEN (-6025 4150);
DISPLAY INVISIBLE (-6025 4150);
FORCEPROP 1 LAST HDL_TAP TRUE
J 0
(-5700 4075);
DISPLAY 0.574468 (-5700 4075);
PAINT GREEN (-5700 4075);
DISPLAY INVISIBLE (-5700 4075);
FORCEPROP 1 LAST PATH I352
J 0
(-6027 4200);
DISPLAY 0.872340 (-6027 4200);
PAINT GREEN (-6027 4200);
DISPLAY INVISIBLE (-6027 4200);
FORCEADD OFFPAGE..1
(-7075 5875);
FORCEPROP 2 LAST $XR0 115 
J 0
(-7327 5875);
DISPLAY 0.638298 (-7327 5875);
PAINT MONO (-7327 5875);
FORCEPROP 2 LAST PATH I353
J 0
(-7025 5950);
DISPLAY 1.021277 (-7025 5950);
DISPLAY INVISIBLE (-7025 5950);
FORCEPROP 1 LAST COMMENT_BODY TRUE
J 0
(-6950 5775);
DISPLAY 0.872340 (-6950 5775);
PAINT GREEN (-6950 5775);
DISPLAY INVISIBLE (-6950 5775);
FORCEPROP 1 LAST OFFPAGE TRUE
J 0
(-6750 5750);
DISPLAY 0.872340 (-6750 5750);
PAINT GREEN (-6750 5750);
DISPLAY INVISIBLE (-6750 5750);
FORCEPROP 2 LAST CDS_LIB standard
J 0
(-7075 5875);
DISPLAY INVISIBLE (-7075 5875);
FORCEADD OFFPAGE..1
(-7075 5825);
FORCEPROP 2 LAST $XR0 115 
J 0
(-7327 5825);
DISPLAY 0.638298 (-7327 5825);
PAINT MONO (-7327 5825);
FORCEPROP 2 LAST PATH I354
J 0
(-7025 5900);
DISPLAY 1.021277 (-7025 5900);
DISPLAY INVISIBLE (-7025 5900);
FORCEPROP 1 LAST COMMENT_BODY TRUE
J 0
(-6950 5725);
DISPLAY 0.872340 (-6950 5725);
PAINT GREEN (-6950 5725);
DISPLAY INVISIBLE (-6950 5725);
FORCEPROP 1 LAST OFFPAGE TRUE
J 0
(-6750 5700);
DISPLAY 0.872340 (-6750 5700);
PAINT GREEN (-6750 5700);
DISPLAY INVISIBLE (-6750 5700);
FORCEPROP 2 LAST CDS_LIB standard
J 0
(-7075 5825);
DISPLAY INVISIBLE (-7075 5825);
FORCEADD QUANTA_TITLE_BLOCK_C..1
(0 0);
FORCEPROP 0 LAST CDS_CON_LAST_MODIFIED Fri Mar 11 14:52:37 2022
J 0
(-1885 15);
DISPLAY INVISIBLE (-1885 15);
FORCEPROP 1 LAST CUSTOM_TXT_CDS <CON_LAST_MODIFIED>
J 0
(-1885 15);
DISPLAY 0.978723 (-1885 15);
FORCEPROP 2 LAST CUSTOM_TXT_CDS <XR_PAGE_TITLE>
J 0
(-7890 5250);
DISPLAY 0.638298 (-7890 5250);
PAINT PINK (-7890 5250);
DISPLAY INVISIBLE (-7890 5250);
FORCEPROP 1 LAST CUSTOM_TXT_CDS <NAME_2>
J 0
(-3175 50);
FORCEPROP 1 LAST CUSTOM_TXT_CDS <NAME_1>
J 0
(-3175 175);
FORCEPROP 1 LAST CUSTOM_TXT_CDS <Q_NUMBER>
J 0
(-1403 103);
DISPLAY 1.212766 (-1403 103);
FORCEPROP 1 LAST CUSTOM_TXT_CDS <Q_PROJ>
J 0
(-2382 102);
DISPLAY 1.212766 (-2382 102);
FORCEPROP 1 LAST CUSTOM_TXT_CDS <Q_REV>
J 0
(-184 103);
DISPLAY 1.212766 (-184 103);
FORCEPROP 1 LAST CUSTOM_TXT_CDS <CON_PAGE_NUM> OF <CON_TOTAL_PAGES>
J 0
(-446 18);
DISPLAY 0.978723 (-446 18);
FORCEPROP 1 LAST Q_TITLE CPU1 PCIE P2/P3
J 0
(-9366 26);
DISPLAY 2.446809 (-9366 26);
PAINT GREEN (-9366 26);
FORCEPROP 1 LAST Q_DEPT BU9
J 1
(-3763 49);
DISPLAY 1.957447 (-3763 49);
PAINT GREEN (-3763 49);
FORCEPROP 2 LAST CDS_LIB pure_quanta
J 0
(0 0);
DISPLAY INVISIBLE (0 0);
FORCEPROP 1 LAST CDS_LMAN_SYM_OUTLINE -9475,6775,100,-125
J 0
(0 0);
DISPLAY 0.468085 (0 0);
PAINT GREEN (0 0);
DISPLAY INVISIBLE (0 0);
FORCEPROP 2 LAST PAGE_BORDER TRUE
J 0
(-7890 5250);
DISPLAY 0.638298 (-7890 5250);
PAINT PINK (-7890 5250);
DISPLAY INVISIBLE (-7890 5250);
FORCEPROP 1 LAST COMMENT_BODY TRUE
J 0
(12 -13);
DISPLAY 0.978723 (12 -13);
PAINT GREEN (12 -13);
DISPLAY INVISIBLE (12 -13);
FORCEPROP 2 LAST CDS_XR_PAGE_TITLE CR-52 : @T6G_MB_LIB.T6G(SCH_1):PAGE52
J 0
(-7890 5250);
DISPLAY 0.638298 (-7890 5250);
PAINT PINK (-7890 5250);
DISPLAY INVISIBLE (-7890 5250);
WIRE 17 -1 (-3400 5675)(-3400 5575);
WIRE 17 -1 (-3400 5875)(-3400 5675);
WIRE 17 -1 (-3400 5575)(-3400 5475);
WIRE 17 -1 (-3400 5475)(-3400 5375);
WIRE 17 -1 (-3400 5875)(-2375 5875);
FORCEPROP 2 LAST SIG_NAME P5E_CPU1_P2_TX_DP<15:0>
J 0
(-3185 5885);
DISPLAY 0.489362 (-3185 5885);
WIRE 17 -1 (-3400 5375)(-3400 5275);
WIRE 17 -1 (-3400 5275)(-3400 5175);
WIRE 17 -1 (-3400 5175)(-3400 5075);
WIRE 17 -1 (-3400 5075)(-3400 4975);
WIRE 17 -1 (-3250 5625)(-3250 5525);
WIRE 17 -1 (-3250 5825)(-3250 5625);
WIRE 17 -1 (-3250 5525)(-3250 5425);
WIRE 17 -1 (-3250 5425)(-3250 5325);
WIRE 17 -1 (-3250 5825)(-2375 5825);
FORCEPROP 2 LAST SIG_NAME P5E_CPU1_P2_TX_DN<15:0>
J 0
(-3185 5835);
DISPLAY 0.489362 (-3185 5835);
WIRE 17 -1 (-3400 4975)(-3400 4875);
WIRE 17 -1 (-3250 5325)(-3250 5225);
WIRE 17 -1 (-3400 4875)(-3400 4775);
WIRE 17 -1 (-3400 4775)(-3400 4675);
WIRE 17 -1 (-3400 4675)(-3400 4575);
WIRE 17 -1 (-3250 5225)(-3250 5125);
WIRE 17 -1 (-3250 5125)(-3250 5025);
WIRE 17 -1 (-3250 5025)(-3250 4925);
WIRE 17 -1 (-3400 4575)(-3400 4475);
WIRE 17 -1 (-3250 4925)(-3250 4825);
WIRE 17 -1 (-3250 4825)(-3250 4725);
WIRE 17 -1 (-3250 4725)(-3250 4625);
WIRE 17 -1 (-3250 4625)(-3250 4525);
WIRE 17 -1 (-3400 4475)(-3400 4375);
WIRE 17 -1 (-3400 4375)(-3400 4275);
WIRE 17 -1 (-3400 4275)(-3400 4175);
WIRE 17 -1 (-3250 4525)(-3250 4425);
WIRE 17 -1 (-3250 4425)(-3250 4325);
WIRE 17 -1 (-3250 4325)(-3250 4225);
WIRE 17 -1 (-3250 4225)(-3250 4125);
WIRE 17 -1 (-3400 3175)(-3400 3075);
WIRE 17 -1 (-3400 3375)(-3400 3175);
WIRE 17 -1 (-3400 3075)(-3400 2975);
WIRE 17 -1 (-3400 2975)(-3400 2875);
WIRE 17 -1 (-3400 3375)(-2375 3375);
FORCEPROP 2 LAST SIG_NAME P5E_CPU1_P3_TX_DN<15:0>
J 0
(-3210 3385);
DISPLAY 0.489362 (-3210 3385);
WIRE 17 -1 (-3250 3125)(-3250 3025);
WIRE 17 -1 (-3250 3325)(-3250 3125);
WIRE 17 -1 (-3250 3025)(-3250 2925);
WIRE 17 -1 (-3250 2925)(-3250 2825);
WIRE 17 -1 (-3250 3325)(-2375 3325);
FORCEPROP 2 LAST SIG_NAME P5E_CPU1_P3_TX_DP<15:0>
J 0
(-3210 3335);
DISPLAY 0.489362 (-3210 3335);
WIRE 17 -1 (-3400 2875)(-3400 2775);
WIRE 17 -1 (-3250 2825)(-3250 2725);
WIRE 17 -1 (-3400 2775)(-3400 2675);
WIRE 17 -1 (-3400 2675)(-3400 2575);
WIRE 17 -1 (-3400 2575)(-3400 2475);
WIRE 17 -1 (-3250 2725)(-3250 2625);
WIRE 17 -1 (-3250 2625)(-3250 2525);
WIRE 17 -1 (-3250 2525)(-3250 2425);
WIRE 17 -1 (-3400 2475)(-3400 2375);
WIRE 17 -1 (-3250 2425)(-3250 2325);
WIRE 17 -1 (-3400 2375)(-3400 2275);
WIRE 17 -1 (-3400 2275)(-3400 2175);
WIRE 17 -1 (-3400 2175)(-3400 2075);
WIRE 17 -1 (-3250 2325)(-3250 2225);
WIRE 17 -1 (-3250 2225)(-3250 2125);
WIRE 17 -1 (-3250 2125)(-3250 2025);
WIRE 17 -1 (-3400 2075)(-3400 1975);
WIRE 17 -1 (-3250 2025)(-3250 1925);
WIRE 17 -1 (-3400 1975)(-3400 1875);
WIRE 17 -1 (-3400 1875)(-3400 1775);
WIRE 17 -1 (-3400 1775)(-3400 1675);
WIRE 17 -1 (-3250 1925)(-3250 1825);
WIRE 17 -1 (-3250 1825)(-3250 1725);
WIRE 17 -1 (-3250 1725)(-3250 1625);
WIRE 17 -1 (-5925 5475)(-5925 5575);
WIRE 17 -1 (-5925 5375)(-5925 5475);
WIRE 17 -1 (-5925 5575)(-5925 5675);
WIRE 17 -1 (-5925 5675)(-5925 5875);
WIRE 17 -1 (-5925 5275)(-5925 5375);
WIRE 17 -1 (-5925 5175)(-5925 5275);
WIRE 17 -1 (-5925 5875)(-7025 5875);
FORCEPROP 2 LAST SIG_NAME P5E_CPU1_P2_RX_DP<15:0>
J 0
(-6960 5885);
DISPLAY 0.489362 (-6960 5885);
WIRE 17 -1 (-5925 5075)(-5925 5175);
WIRE 17 -1 (-5925 4975)(-5925 5075);
WIRE 17 -1 (-5925 4875)(-5925 4975);
WIRE 17 -1 (-5925 4775)(-5925 4875);
WIRE 17 -1 (-6075 5525)(-6075 5625);
WIRE 17 -1 (-6075 5425)(-6075 5525);
WIRE 17 -1 (-6075 5625)(-6075 5825);
WIRE 17 -1 (-6075 5825)(-7025 5825);
FORCEPROP 2 LAST SIG_NAME P5E_CPU1_P2_RX_DN<15:0>
J 0
(-6960 5835);
DISPLAY 0.489362 (-6960 5835);
WIRE 17 -1 (-5925 4675)(-5925 4775);
WIRE 17 -1 (-6075 5325)(-6075 5425);
WIRE 17 -1 (-6075 5225)(-6075 5325);
WIRE 17 -1 (-6075 5125)(-6075 5225);
WIRE 17 -1 (-6075 5025)(-6075 5125);
WIRE 17 -1 (-6075 4925)(-6075 5025);
WIRE 17 -1 (-6075 4825)(-6075 4925);
WIRE 17 -1 (-6075 4725)(-6075 4825);
WIRE 17 -1 (-6075 4625)(-6075 4725);
WIRE 17 -1 (-5925 4575)(-5925 4675);
WIRE 17 -1 (-5925 4475)(-5925 4575);
WIRE 17 -1 (-5925 4375)(-5925 4475);
WIRE 17 -1 (-5925 4275)(-5925 4375);
WIRE 17 -1 (-5925 4175)(-5925 4275);
WIRE 17 -1 (-6075 4525)(-6075 4625);
WIRE 17 -1 (-6075 4425)(-6075 4525);
WIRE 17 -1 (-6075 4325)(-6075 4425);
WIRE 17 -1 (-6075 4225)(-6075 4325);
WIRE 17 -1 (-6075 4125)(-6075 4225);
WIRE 17 -1 (-5925 3075)(-5925 3175);
WIRE 17 -1 (-5925 2975)(-5925 3075);
WIRE 17 -1 (-5925 3175)(-5925 3375);
WIRE 17 -1 (-5925 3375)(-7025 3375);
FORCEPROP 2 LAST SIG_NAME P5E_CPU1_P3_RX_DP<15:0>
J 0
(-6985 3385);
DISPLAY 0.489362 (-6985 3385);
WIRE 17 -1 (-6075 3025)(-6075 3125);
WIRE 17 -1 (-6075 2925)(-6075 3025);
WIRE 17 -1 (-6075 3125)(-6075 3325);
WIRE 17 -1 (-7025 3325)(-6075 3325);
FORCEPROP 2 LAST SIG_NAME P5E_CPU1_P3_RX_DN<15:0>
J 0
(-6985 3335);
DISPLAY 0.489362 (-6985 3335);
WIRE 17 -1 (-5925 2875)(-5925 2975);
WIRE 17 -1 (-5925 2775)(-5925 2875);
WIRE 17 -1 (-5925 2675)(-5925 2775);
WIRE 17 -1 (-6075 2825)(-6075 2925);
WIRE 17 -1 (-6075 2725)(-6075 2825);
WIRE 17 -1 (-6075 2625)(-6075 2725);
WIRE 17 -1 (-5925 2575)(-5925 2675);
WIRE 17 -1 (-6075 2525)(-6075 2625);
WIRE 17 -1 (-5925 2475)(-5925 2575);
WIRE 17 -1 (-5925 2375)(-5925 2475);
WIRE 17 -1 (-5925 2275)(-5925 2375);
WIRE 17 -1 (-6075 2425)(-6075 2525);
WIRE 17 -1 (-6075 2325)(-6075 2425);
WIRE 17 -1 (-6075 2225)(-6075 2325);
WIRE 17 -1 (-5925 2175)(-5925 2275);
WIRE 17 -1 (-6075 2125)(-6075 2225);
WIRE 17 -1 (-5925 2075)(-5925 2175);
WIRE 17 -1 (-5925 1975)(-5925 2075);
WIRE 17 -1 (-5925 1875)(-5925 1975);
WIRE 17 -1 (-6075 2025)(-6075 2125);
WIRE 17 -1 (-6075 1925)(-6075 2025);
WIRE 17 -1 (-6075 1825)(-6075 1925);
WIRE 17 -1 (-5925 1775)(-5925 1875);
WIRE 17 -1 (-6075 1725)(-6075 1825);
WIRE 17 -1 (-5925 1675)(-5925 1775);
WIRE 17 -1 (-6075 1625)(-6075 1725);
WIRE 16 -1 (-5975 4700)(-5375 4700);
WIRE 16 -1 (-5825 5050)(-5375 5050);
WIRE 16 -1 (-5975 5100)(-5375 5100);
WIRE 16 -1 (-5825 5150)(-5375 5150);
WIRE 16 -1 (-5825 5650)(-5375 5650);
WIRE 16 -1 (-5975 5600)(-5375 5600);
WIRE 16 -1 (-5825 5550)(-5375 5550);
WIRE 16 -1 (-5975 5300)(-5375 5300);
WIRE 16 -1 (-5975 1600)(-5375 1600);
WIRE 16 -1 (-5825 1650)(-5375 1650);
WIRE 16 -1 (-5975 1700)(-5375 1700);
WIRE 16 -1 (-5825 1750)(-5375 1750);
WIRE 16 -1 (-5975 1800)(-5375 1800);
WIRE 16 -1 (-5825 1850)(-5375 1850);
WIRE 16 -1 (-5975 1900)(-5375 1900);
WIRE 16 -1 (-5825 1950)(-5375 1950);
WIRE 16 -1 (-5975 2000)(-5375 2000);
WIRE 16 -1 (-5825 2050)(-5375 2050);
WIRE 16 -1 (-5975 2100)(-5375 2100);
WIRE 16 -1 (-5825 2150)(-5375 2150);
WIRE 16 -1 (-5975 2200)(-5375 2200);
WIRE 16 -1 (-5825 2250)(-5375 2250);
WIRE 16 -1 (-5975 2300)(-5375 2300);
WIRE 16 -1 (-5825 2350)(-5375 2350);
WIRE 16 -1 (-5975 2400)(-5375 2400);
WIRE 16 -1 (-5825 2450)(-5375 2450);
WIRE 16 -1 (-5975 2500)(-5375 2500);
WIRE 16 -1 (-5825 2550)(-5375 2550);
WIRE 16 -1 (-5975 2600)(-5375 2600);
WIRE 16 -1 (-5825 2650)(-5375 2650);
WIRE 16 -1 (-5975 2700)(-5375 2700);
WIRE 16 -1 (-5825 2750)(-5375 2750);
WIRE 16 -1 (-5975 2800)(-5375 2800);
WIRE 16 -1 (-5825 2850)(-5375 2850);
WIRE 16 -1 (-5975 2900)(-5375 2900);
WIRE 16 -1 (-5825 2950)(-5375 2950);
WIRE 16 -1 (-5975 3000)(-5375 3000);
WIRE 16 -1 (-5825 3050)(-5375 3050);
WIRE 16 -1 (-5975 3100)(-5375 3100);
WIRE 16 -1 (-5825 3150)(-5375 3150);
WIRE 16 -1 (-5975 4900)(-5375 4900);
WIRE 16 -1 (-5975 5000)(-5375 5000);
WIRE 16 -1 (-5825 4950)(-5375 4950);
WIRE 16 -1 (-5975 4100)(-5375 4100);
WIRE 16 -1 (-5825 4150)(-5375 4150);
WIRE 16 -1 (-5975 4200)(-5375 4200);
WIRE 16 -1 (-5825 4250)(-5375 4250);
WIRE 16 -1 (-5975 4300)(-5375 4300);
WIRE 16 -1 (-5825 4350)(-5375 4350);
WIRE 16 -1 (-5975 4400)(-5375 4400);
WIRE 16 -1 (-5825 4450)(-5375 4450);
WIRE 16 -1 (-5975 4500)(-5375 4500);
WIRE 16 -1 (-5825 4550)(-5375 4550);
WIRE 16 -1 (-5975 4600)(-5375 4600);
WIRE 16 -1 (-5825 4650)(-5375 4650);
WIRE 16 -1 (-5825 4750)(-5375 4750);
WIRE 16 -1 (-5975 4800)(-5375 4800);
WIRE 16 -1 (-5825 4850)(-5375 4850);
WIRE 16 -1 (-5975 5200)(-5375 5200);
WIRE 16 -1 (-5975 5400)(-5375 5400);
WIRE 16 -1 (-5825 5250)(-5375 5250);
WIRE 16 -1 (-5975 5500)(-5375 5500);
WIRE 16 -1 (-5825 5350)(-5375 5350);
WIRE 16 -1 (-5825 5450)(-5375 5450);
WIRE 16 -1 (-3875 1600)(-3350 1600);
WIRE 16 -1 (-3875 1650)(-3500 1650);
WIRE 16 -1 (-3875 1700)(-3350 1700);
WIRE 16 -1 (-3875 1750)(-3500 1750);
WIRE 16 -1 (-3875 1800)(-3350 1800);
WIRE 16 -1 (-3875 1850)(-3500 1850);
WIRE 16 -1 (-3875 1900)(-3350 1900);
WIRE 16 -1 (-3875 1950)(-3500 1950);
WIRE 16 -1 (-3875 2000)(-3350 2000);
WIRE 16 -1 (-3875 2050)(-3500 2050);
WIRE 16 -1 (-3875 2100)(-3350 2100);
WIRE 16 -1 (-3875 2150)(-3500 2150);
WIRE 16 -1 (-3875 2200)(-3350 2200);
WIRE 16 -1 (-3875 2250)(-3500 2250);
WIRE 16 -1 (-3875 2300)(-3350 2300);
WIRE 16 -1 (-3875 2350)(-3500 2350);
WIRE 16 -1 (-3875 2400)(-3350 2400);
WIRE 16 -1 (-3875 2450)(-3500 2450);
WIRE 16 -1 (-3875 2500)(-3350 2500);
WIRE 16 -1 (-3875 2550)(-3500 2550);
WIRE 16 -1 (-3875 2600)(-3350 2600);
WIRE 16 -1 (-3875 2650)(-3500 2650);
WIRE 16 -1 (-3875 2700)(-3350 2700);
WIRE 16 -1 (-3875 2750)(-3500 2750);
WIRE 16 -1 (-3875 2800)(-3350 2800);
WIRE 16 -1 (-3875 2850)(-3500 2850);
WIRE 16 -1 (-3875 2900)(-3350 2900);
WIRE 16 -1 (-3875 2950)(-3500 2950);
WIRE 16 -1 (-3875 3000)(-3350 3000);
WIRE 16 -1 (-3875 3050)(-3500 3050);
WIRE 16 -1 (-3875 3100)(-3350 3100);
WIRE 16 -1 (-3875 3150)(-3500 3150);
WIRE 16 -1 (-3875 4900)(-3350 4900);
WIRE 16 -1 (-3875 5000)(-3350 5000);
WIRE 16 -1 (-3875 5100)(-3350 5100);
WIRE 16 -1 (-3875 4950)(-3500 4950);
WIRE 16 -1 (-3875 5050)(-3500 5050);
WIRE 16 -1 (-3875 4100)(-3350 4100);
WIRE 16 -1 (-3875 4150)(-3500 4150);
WIRE 16 -1 (-3875 4200)(-3350 4200);
WIRE 16 -1 (-3875 4250)(-3500 4250);
WIRE 16 -1 (-3875 4300)(-3350 4300);
WIRE 16 -1 (-3875 4350)(-3500 4350);
WIRE 16 -1 (-3875 4400)(-3350 4400);
WIRE 16 -1 (-3875 4450)(-3500 4450);
WIRE 16 -1 (-3875 4500)(-3350 4500);
WIRE 16 -1 (-3875 4550)(-3500 4550);
WIRE 16 -1 (-3875 4600)(-3350 4600);
WIRE 16 -1 (-3875 4650)(-3500 4650);
WIRE 16 -1 (-3875 4700)(-3350 4700);
WIRE 16 -1 (-3875 4750)(-3500 4750);
WIRE 16 -1 (-3875 4800)(-3350 4800);
WIRE 16 -1 (-3875 4850)(-3500 4850);
WIRE 16 -1 (-3875 5200)(-3350 5200);
WIRE 16 -1 (-3875 5300)(-3350 5300);
WIRE 16 -1 (-3875 5150)(-3500 5150);
WIRE 16 -1 (-3875 5400)(-3350 5400);
WIRE 16 -1 (-3875 5250)(-3500 5250);
WIRE 16 -1 (-3875 5500)(-3350 5500);
WIRE 16 -1 (-3875 5350)(-3500 5350);
WIRE 16 -1 (-3875 5600)(-3350 5600);
WIRE 16 -1 (-3875 5450)(-3500 5450);
WIRE 16 -1 (-3875 5550)(-3500 5550);
WIRE 16 -1 (-3875 5650)(-3500 5650);
FORCENOTE
(TX PN SWAP)
(-2450 1725) 0;
DISPLAY LEFT (-2450 1725);
DISPLAY 2.000000 (-2450 1725);
FORCENOTE
(TX PN SWAP)
(-2450 2175) 0;
DISPLAY LEFT (-2450 2175);
DISPLAY 2.000000 (-2450 2175);
FORCENOTE
(TX PN SWAP)
(-2450 2525) 0;
DISPLAY LEFT (-2450 2525);
DISPLAY 2.000000 (-2450 2525);
FORCENOTE
CPU1 P3[11:8] TO E1.S#4
(-2425 2300) 0;
DISPLAY LEFT (-2425 2300);
DISPLAY 2.000000 (-2425 2300);
FORCENOTE
CPU1 P3[15:12] TO E1.S#3
(-2450 1850) 0;
DISPLAY LEFT (-2450 1850);
DISPLAY 2.000000 (-2450 1850);
FORCENOTE
CPU1 P3[7:0] TO OCP NIC
(-2425 2675) 0;
DISPLAY LEFT (-2425 2675);
DISPLAY 2.000000 (-2425 2675);
FORCENOTE
CPU1 P2[15:0] TO SLOT#2
(-2475 4775) 0;
DISPLAY LEFT (-2475 4775);
DISPLAY 2.000000 (-2475 4775);
QUIT
